FILE_TYPE = MACRO_DRAWING;
SET COLOR_WIRE YELLOW;
SET COLOR_PROP ORANGE;
SET COLOR_DOT WHITE;
SET COLOR_ARC YELLOW;
SET COLOR_BODY GREEN;
SET COLOR_NOTE PURPLE;
SET PROP_DISPLAY VALUE;
SET PAGE_NUMBER P105;
FORCEADD OFFPAGE..5
(-8275 1900);
FORCEPROP 2 LAST $XR0 45 
J 0
(-8529 1900);
DISPLAY 0.638298 (-8529 1900);
PAINT MONO (-8529 1900);
FORCEPROP 2 LAST CDS_LIB mstr_standard
J 0
(-8275 1900);
DISPLAY 0.808511 (-8275 1900);
DISPLAY INVISIBLE (-8275 1900);
FORCEPROP 1 LAST OFFPAGE TRUE
J 0
(-7950 1775);
DISPLAY 0.872340 (-7950 1775);
PAINT GREEN (-7950 1775);
DISPLAY INVISIBLE (-7950 1775);
FORCEPROP 1 LAST COMMENT_BODY TRUE
J 0
(-8175 1825);
DISPLAY 0.872340 (-8175 1825);
PAINT GREEN (-8175 1825);
DISPLAY INVISIBLE (-8175 1825);
FORCEPROP 2 LAST PATH I1
J 0
(-8475 1950);
DISPLAY 1.021277 (-8475 1950);
DISPLAY INVISIBLE (-8475 1950);
FORCEADD OFFPAGE..6
(-8275 3550);
FORCEPROP 2 LAST $XR0 45 
J 0
(-8554 3550);
DISPLAY 0.638298 (-8554 3550);
PAINT MONO (-8554 3550);
FORCEPROP 2 LAST CDS_LIB mstr_standard
J 0
(-8275 3550);
DISPLAY 0.723404 (-8275 3550);
PAINT MONO (-8275 3550);
DISPLAY INVISIBLE (-8275 3550);
FORCEPROP 1 LAST OFFPAGE TRUE
J 0
(-7950 3425);
DISPLAY 0.872340 (-7950 3425);
PAINT GREEN (-7950 3425);
DISPLAY INVISIBLE (-7950 3425);
FORCEPROP 1 LAST COMMENT_BODY TRUE
J 0
(-8175 3475);
DISPLAY 0.872340 (-8175 3475);
PAINT GREEN (-8175 3475);
DISPLAY INVISIBLE (-8175 3475);
FORCEPROP 2 LAST PATH I10
J 0
(-8550 3600);
DISPLAY 1.021277 (-8550 3600);
DISPLAY INVISIBLE (-8550 3600);
FORCEADD TAP..1
(-5975 4150);
FORCEPROP 3 LASTPIN (-6025 4150) SIG_NAME M_I_CPU1_SA_DQ<7>
J 0
(-6015 4160);
DISPLAY 0.659574 (-6015 4160);
PAINT MONO (-6015 4160);
DISPLAY INVISIBLE (-6015 4160);
FORCEPROP 1 LASTPIN (-6025 4150) BN 7
J 0
(-6037 4158);
DISPLAY 0.489362 (-6037 4158);
PAINT GREEN (-6037 4158);
FORCEPROP 2 LAST CDS_LIB mstr_standard
J 0
(-5975 4150);
DISPLAY 0.723404 (-5975 4150);
PAINT MONO (-5975 4150);
DISPLAY INVISIBLE (-5975 4150);
FORCEPROP 1 LAST BODY_TYPE PLUMBING
J 0
(-5975 4200);
DISPLAY 0.872340 (-5975 4200);
PAINT GREEN (-5975 4200);
DISPLAY INVISIBLE (-5975 4200);
FORCEPROP 1 LAST HDL_TAP TRUE
J 0
(-5650 4025);
DISPLAY 0.872340 (-5650 4025);
DISPLAY INVISIBLE (-5650 4025);
FORCEPROP 1 LAST PATH I100
J 0
(-5977 4150);
DISPLAY 0.872340 (-5977 4150);
PAINT GREEN (-5977 4150);
DISPLAY INVISIBLE (-5977 4150);
FORCEADD TAP..1
(-5975 4300);
FORCEPROP 3 LASTPIN (-6025 4300) SIG_NAME M_I_CPU1_SA_DQ<10>
J 0
(-6015 4310);
DISPLAY 0.659574 (-6015 4310);
PAINT MONO (-6015 4310);
DISPLAY INVISIBLE (-6015 4310);
FORCEPROP 1 LASTPIN (-6025 4300) BN 10
J 0
(-6037 4308);
DISPLAY 0.489362 (-6037 4308);
PAINT GREEN (-6037 4308);
FORCEPROP 2 LAST CDS_LIB mstr_standard
J 0
(-5975 4300);
DISPLAY 0.723404 (-5975 4300);
PAINT MONO (-5975 4300);
DISPLAY INVISIBLE (-5975 4300);
FORCEPROP 1 LAST BODY_TYPE PLUMBING
J 0
(-5975 4350);
DISPLAY 0.872340 (-5975 4350);
PAINT GREEN (-5975 4350);
DISPLAY INVISIBLE (-5975 4350);
FORCEPROP 1 LAST HDL_TAP TRUE
J 0
(-5650 4175);
DISPLAY 0.872340 (-5650 4175);
DISPLAY INVISIBLE (-5650 4175);
FORCEPROP 1 LAST PATH I101
J 0
(-5977 4300);
DISPLAY 0.872340 (-5977 4300);
PAINT GREEN (-5977 4300);
DISPLAY INVISIBLE (-5977 4300);
FORCEADD TAP..1
(-5975 4250);
FORCEPROP 3 LASTPIN (-6025 4250) SIG_NAME M_I_CPU1_SA_DQ<9>
J 0
(-6015 4260);
DISPLAY 0.659574 (-6015 4260);
PAINT MONO (-6015 4260);
DISPLAY INVISIBLE (-6015 4260);
FORCEPROP 1 LASTPIN (-6025 4250) BN 9
J 0
(-6037 4258);
DISPLAY 0.489362 (-6037 4258);
PAINT GREEN (-6037 4258);
FORCEPROP 2 LAST CDS_LIB mstr_standard
J 0
(-5975 4250);
DISPLAY 0.723404 (-5975 4250);
PAINT MONO (-5975 4250);
DISPLAY INVISIBLE (-5975 4250);
FORCEPROP 1 LAST BODY_TYPE PLUMBING
J 0
(-5975 4300);
DISPLAY 0.872340 (-5975 4300);
PAINT GREEN (-5975 4300);
DISPLAY INVISIBLE (-5975 4300);
FORCEPROP 1 LAST HDL_TAP TRUE
J 0
(-5650 4125);
DISPLAY 0.872340 (-5650 4125);
DISPLAY INVISIBLE (-5650 4125);
FORCEPROP 1 LAST PATH I102
J 0
(-5977 4250);
DISPLAY 0.872340 (-5977 4250);
PAINT GREEN (-5977 4250);
DISPLAY INVISIBLE (-5977 4250);
FORCEADD TAP..1
(-5975 4200);
FORCEPROP 3 LASTPIN (-6025 4200) SIG_NAME M_I_CPU1_SA_DQ<8>
J 0
(-6015 4210);
DISPLAY 0.659574 (-6015 4210);
PAINT MONO (-6015 4210);
DISPLAY INVISIBLE (-6015 4210);
FORCEPROP 1 LASTPIN (-6025 4200) BN 8
J 0
(-6037 4208);
DISPLAY 0.489362 (-6037 4208);
PAINT GREEN (-6037 4208);
FORCEPROP 2 LAST CDS_LIB mstr_standard
J 0
(-5975 4200);
DISPLAY 0.723404 (-5975 4200);
PAINT MONO (-5975 4200);
DISPLAY INVISIBLE (-5975 4200);
FORCEPROP 1 LAST BODY_TYPE PLUMBING
J 0
(-5975 4250);
DISPLAY 0.872340 (-5975 4250);
PAINT GREEN (-5975 4250);
DISPLAY INVISIBLE (-5975 4250);
FORCEPROP 1 LAST HDL_TAP TRUE
J 0
(-5650 4075);
DISPLAY 0.872340 (-5650 4075);
DISPLAY INVISIBLE (-5650 4075);
FORCEPROP 1 LAST PATH I103
J 0
(-5977 4200);
DISPLAY 0.872340 (-5977 4200);
PAINT GREEN (-5977 4200);
DISPLAY INVISIBLE (-5977 4200);
FORCEADD TAP..1
(-5975 4350);
FORCEPROP 3 LASTPIN (-6025 4350) SIG_NAME M_I_CPU1_SA_DQ<11>
J 0
(-6015 4360);
DISPLAY 0.659574 (-6015 4360);
PAINT MONO (-6015 4360);
DISPLAY INVISIBLE (-6015 4360);
FORCEPROP 1 LASTPIN (-6025 4350) BN 11
J 0
(-6037 4358);
DISPLAY 0.489362 (-6037 4358);
PAINT GREEN (-6037 4358);
FORCEPROP 2 LAST CDS_LIB mstr_standard
J 0
(-5975 4350);
DISPLAY 0.723404 (-5975 4350);
PAINT MONO (-5975 4350);
DISPLAY INVISIBLE (-5975 4350);
FORCEPROP 1 LAST BODY_TYPE PLUMBING
J 0
(-5975 4400);
DISPLAY 0.872340 (-5975 4400);
PAINT GREEN (-5975 4400);
DISPLAY INVISIBLE (-5975 4400);
FORCEPROP 1 LAST HDL_TAP TRUE
J 0
(-5650 4225);
DISPLAY 0.872340 (-5650 4225);
DISPLAY INVISIBLE (-5650 4225);
FORCEPROP 1 LAST PATH I104
J 0
(-5977 4350);
DISPLAY 0.872340 (-5977 4350);
PAINT GREEN (-5977 4350);
DISPLAY INVISIBLE (-5977 4350);
FORCEADD TAP..1
(-5975 4400);
FORCEPROP 3 LASTPIN (-6025 4400) SIG_NAME M_I_CPU1_SA_DQ<12>
J 0
(-6015 4410);
DISPLAY 0.659574 (-6015 4410);
PAINT MONO (-6015 4410);
DISPLAY INVISIBLE (-6015 4410);
FORCEPROP 1 LASTPIN (-6025 4400) BN 12
J 0
(-6037 4408);
DISPLAY 0.489362 (-6037 4408);
PAINT GREEN (-6037 4408);
FORCEPROP 2 LAST CDS_LIB mstr_standard
J 0
(-5975 4400);
DISPLAY 0.723404 (-5975 4400);
PAINT MONO (-5975 4400);
DISPLAY INVISIBLE (-5975 4400);
FORCEPROP 1 LAST BODY_TYPE PLUMBING
J 0
(-5975 4450);
DISPLAY 0.872340 (-5975 4450);
PAINT GREEN (-5975 4450);
DISPLAY INVISIBLE (-5975 4450);
FORCEPROP 1 LAST HDL_TAP TRUE
J 0
(-5650 4275);
DISPLAY 0.872340 (-5650 4275);
DISPLAY INVISIBLE (-5650 4275);
FORCEPROP 1 LAST PATH I105
J 0
(-5977 4400);
DISPLAY 0.872340 (-5977 4400);
PAINT GREEN (-5977 4400);
DISPLAY INVISIBLE (-5977 4400);
FORCEADD TAP..1
(-5975 4450);
FORCEPROP 3 LASTPIN (-6025 4450) SIG_NAME M_I_CPU1_SA_DQ<13>
J 0
(-6015 4460);
DISPLAY 0.659574 (-6015 4460);
PAINT MONO (-6015 4460);
DISPLAY INVISIBLE (-6015 4460);
FORCEPROP 1 LASTPIN (-6025 4450) BN 13
J 0
(-6037 4458);
DISPLAY 0.489362 (-6037 4458);
PAINT GREEN (-6037 4458);
FORCEPROP 2 LAST CDS_LIB mstr_standard
J 0
(-5975 4450);
DISPLAY 0.723404 (-5975 4450);
PAINT MONO (-5975 4450);
DISPLAY INVISIBLE (-5975 4450);
FORCEPROP 1 LAST BODY_TYPE PLUMBING
J 0
(-5975 4500);
DISPLAY 0.872340 (-5975 4500);
PAINT GREEN (-5975 4500);
DISPLAY INVISIBLE (-5975 4500);
FORCEPROP 1 LAST HDL_TAP TRUE
J 0
(-5650 4325);
DISPLAY 0.872340 (-5650 4325);
DISPLAY INVISIBLE (-5650 4325);
FORCEPROP 1 LAST PATH I106
J 0
(-5977 4450);
DISPLAY 0.872340 (-5977 4450);
PAINT GREEN (-5977 4450);
DISPLAY INVISIBLE (-5977 4450);
FORCEADD TAP..1
(-5975 4500);
FORCEPROP 3 LASTPIN (-6025 4500) SIG_NAME M_I_CPU1_SA_DQ<14>
J 0
(-6015 4510);
DISPLAY 0.659574 (-6015 4510);
PAINT MONO (-6015 4510);
DISPLAY INVISIBLE (-6015 4510);
FORCEPROP 1 LASTPIN (-6025 4500) BN 14
J 0
(-6037 4508);
DISPLAY 0.489362 (-6037 4508);
PAINT GREEN (-6037 4508);
FORCEPROP 2 LAST CDS_LIB mstr_standard
J 0
(-5975 4500);
DISPLAY 0.723404 (-5975 4500);
PAINT MONO (-5975 4500);
DISPLAY INVISIBLE (-5975 4500);
FORCEPROP 1 LAST BODY_TYPE PLUMBING
J 0
(-5975 4550);
DISPLAY 0.872340 (-5975 4550);
PAINT GREEN (-5975 4550);
DISPLAY INVISIBLE (-5975 4550);
FORCEPROP 1 LAST HDL_TAP TRUE
J 0
(-5650 4375);
DISPLAY 0.872340 (-5650 4375);
DISPLAY INVISIBLE (-5650 4375);
FORCEPROP 1 LAST PATH I107
J 0
(-5977 4500);
DISPLAY 0.872340 (-5977 4500);
PAINT GREEN (-5977 4500);
DISPLAY INVISIBLE (-5977 4500);
FORCEADD TAP..1
(-5975 4550);
FORCEPROP 3 LASTPIN (-6025 4550) SIG_NAME M_I_CPU1_SA_DQ<15>
J 0
(-6015 4560);
DISPLAY 0.659574 (-6015 4560);
PAINT MONO (-6015 4560);
DISPLAY INVISIBLE (-6015 4560);
FORCEPROP 1 LASTPIN (-6025 4550) BN 15
J 0
(-6037 4558);
DISPLAY 0.489362 (-6037 4558);
PAINT GREEN (-6037 4558);
FORCEPROP 2 LAST CDS_LIB mstr_standard
J 0
(-5975 4550);
DISPLAY 0.723404 (-5975 4550);
PAINT MONO (-5975 4550);
DISPLAY INVISIBLE (-5975 4550);
FORCEPROP 1 LAST BODY_TYPE PLUMBING
J 0
(-5975 4600);
DISPLAY 0.872340 (-5975 4600);
PAINT GREEN (-5975 4600);
DISPLAY INVISIBLE (-5975 4600);
FORCEPROP 1 LAST HDL_TAP TRUE
J 0
(-5650 4425);
DISPLAY 0.872340 (-5650 4425);
DISPLAY INVISIBLE (-5650 4425);
FORCEPROP 1 LAST PATH I108
J 0
(-5977 4550);
DISPLAY 0.872340 (-5977 4550);
PAINT GREEN (-5977 4550);
DISPLAY INVISIBLE (-5977 4550);
FORCEADD TAP..1
(-5975 4650);
FORCEPROP 3 LASTPIN (-6025 4650) SIG_NAME M_I_CPU1_SA_DQ<17>
J 0
(-6015 4660);
DISPLAY 0.659574 (-6015 4660);
PAINT MONO (-6015 4660);
DISPLAY INVISIBLE (-6015 4660);
FORCEPROP 1 LASTPIN (-6025 4650) BN 17
J 0
(-6037 4658);
DISPLAY 0.489362 (-6037 4658);
PAINT GREEN (-6037 4658);
FORCEPROP 2 LAST CDS_LIB mstr_standard
J 0
(-5975 4650);
DISPLAY 0.723404 (-5975 4650);
PAINT MONO (-5975 4650);
DISPLAY INVISIBLE (-5975 4650);
FORCEPROP 1 LAST BODY_TYPE PLUMBING
J 0
(-5975 4700);
DISPLAY 0.872340 (-5975 4700);
PAINT GREEN (-5975 4700);
DISPLAY INVISIBLE (-5975 4700);
FORCEPROP 1 LAST HDL_TAP TRUE
J 0
(-5650 4525);
DISPLAY 0.872340 (-5650 4525);
DISPLAY INVISIBLE (-5650 4525);
FORCEPROP 1 LAST PATH I109
J 0
(-5977 4650);
DISPLAY 0.872340 (-5977 4650);
PAINT GREEN (-5977 4650);
DISPLAY INVISIBLE (-5977 4650);
FORCEADD OFFPAGE..6
(-8275 4000);
FORCEPROP 2 LAST $XR0 45 
J 0
(-8554 4000);
DISPLAY 0.638298 (-8554 4000);
PAINT MONO (-8554 4000);
FORCEPROP 2 LAST CDS_LIB mstr_standard
J 0
(-8275 4000);
DISPLAY 0.723404 (-8275 4000);
PAINT MONO (-8275 4000);
DISPLAY INVISIBLE (-8275 4000);
FORCEPROP 1 LAST OFFPAGE TRUE
J 0
(-7950 3875);
DISPLAY 0.872340 (-7950 3875);
PAINT GREEN (-7950 3875);
DISPLAY INVISIBLE (-7950 3875);
FORCEPROP 1 LAST COMMENT_BODY TRUE
J 0
(-8175 3925);
DISPLAY 0.872340 (-8175 3925);
PAINT GREEN (-8175 3925);
DISPLAY INVISIBLE (-8175 3925);
FORCEPROP 2 LAST PATH I11
J 0
(-8550 4050);
DISPLAY 1.021277 (-8550 4050);
DISPLAY INVISIBLE (-8550 4050);
FORCEADD TAP..1
(-5975 4600);
FORCEPROP 3 LASTPIN (-6025 4600) SIG_NAME M_I_CPU1_SA_DQ<16>
J 0
(-6015 4610);
DISPLAY 0.659574 (-6015 4610);
PAINT MONO (-6015 4610);
DISPLAY INVISIBLE (-6015 4610);
FORCEPROP 1 LASTPIN (-6025 4600) BN 16
J 0
(-6037 4608);
DISPLAY 0.489362 (-6037 4608);
PAINT GREEN (-6037 4608);
FORCEPROP 2 LAST CDS_LIB mstr_standard
J 0
(-5975 4600);
DISPLAY 0.723404 (-5975 4600);
PAINT MONO (-5975 4600);
DISPLAY INVISIBLE (-5975 4600);
FORCEPROP 1 LAST BODY_TYPE PLUMBING
J 0
(-5975 4650);
DISPLAY 0.872340 (-5975 4650);
PAINT GREEN (-5975 4650);
DISPLAY INVISIBLE (-5975 4650);
FORCEPROP 1 LAST HDL_TAP TRUE
J 0
(-5650 4475);
DISPLAY 0.872340 (-5650 4475);
DISPLAY INVISIBLE (-5650 4475);
FORCEPROP 1 LAST PATH I110
J 0
(-5977 4600);
DISPLAY 0.872340 (-5977 4600);
PAINT GREEN (-5977 4600);
DISPLAY INVISIBLE (-5977 4600);
FORCEADD TAP..1
(-5975 4800);
FORCEPROP 3 LASTPIN (-6025 4800) SIG_NAME M_I_CPU1_SA_DQ<20>
J 0
(-6015 4810);
DISPLAY 0.659574 (-6015 4810);
PAINT MONO (-6015 4810);
DISPLAY INVISIBLE (-6015 4810);
FORCEPROP 1 LASTPIN (-6025 4800) BN 20
J 0
(-6037 4808);
DISPLAY 0.489362 (-6037 4808);
PAINT GREEN (-6037 4808);
FORCEPROP 2 LAST CDS_LIB mstr_standard
J 0
(-5975 4800);
DISPLAY 0.723404 (-5975 4800);
PAINT MONO (-5975 4800);
DISPLAY INVISIBLE (-5975 4800);
FORCEPROP 1 LAST BODY_TYPE PLUMBING
J 0
(-5975 4850);
DISPLAY 0.872340 (-5975 4850);
PAINT GREEN (-5975 4850);
DISPLAY INVISIBLE (-5975 4850);
FORCEPROP 1 LAST HDL_TAP TRUE
J 0
(-5650 4675);
DISPLAY 0.872340 (-5650 4675);
DISPLAY INVISIBLE (-5650 4675);
FORCEPROP 1 LAST PATH I111
J 0
(-5977 4800);
DISPLAY 0.872340 (-5977 4800);
PAINT GREEN (-5977 4800);
DISPLAY INVISIBLE (-5977 4800);
FORCEADD TAP..1
(-5975 4750);
FORCEPROP 3 LASTPIN (-6025 4750) SIG_NAME M_I_CPU1_SA_DQ<19>
J 0
(-6015 4760);
DISPLAY 0.659574 (-6015 4760);
PAINT MONO (-6015 4760);
DISPLAY INVISIBLE (-6015 4760);
FORCEPROP 1 LASTPIN (-6025 4750) BN 19
J 0
(-6037 4758);
DISPLAY 0.489362 (-6037 4758);
PAINT GREEN (-6037 4758);
FORCEPROP 2 LAST CDS_LIB mstr_standard
J 0
(-5975 4750);
DISPLAY 0.723404 (-5975 4750);
PAINT MONO (-5975 4750);
DISPLAY INVISIBLE (-5975 4750);
FORCEPROP 1 LAST BODY_TYPE PLUMBING
J 0
(-5975 4800);
DISPLAY 0.872340 (-5975 4800);
PAINT GREEN (-5975 4800);
DISPLAY INVISIBLE (-5975 4800);
FORCEPROP 1 LAST HDL_TAP TRUE
J 0
(-5650 4625);
DISPLAY 0.872340 (-5650 4625);
DISPLAY INVISIBLE (-5650 4625);
FORCEPROP 1 LAST PATH I112
J 0
(-5977 4750);
DISPLAY 0.872340 (-5977 4750);
PAINT GREEN (-5977 4750);
DISPLAY INVISIBLE (-5977 4750);
FORCEADD TAP..1
(-5975 4700);
FORCEPROP 3 LASTPIN (-6025 4700) SIG_NAME M_I_CPU1_SA_DQ<18>
J 0
(-6015 4710);
DISPLAY 0.659574 (-6015 4710);
PAINT MONO (-6015 4710);
DISPLAY INVISIBLE (-6015 4710);
FORCEPROP 1 LASTPIN (-6025 4700) BN 18
J 0
(-6037 4708);
DISPLAY 0.489362 (-6037 4708);
PAINT GREEN (-6037 4708);
FORCEPROP 2 LAST CDS_LIB mstr_standard
J 0
(-5975 4700);
DISPLAY 0.723404 (-5975 4700);
PAINT MONO (-5975 4700);
DISPLAY INVISIBLE (-5975 4700);
FORCEPROP 1 LAST BODY_TYPE PLUMBING
J 0
(-5975 4750);
DISPLAY 0.872340 (-5975 4750);
PAINT GREEN (-5975 4750);
DISPLAY INVISIBLE (-5975 4750);
FORCEPROP 1 LAST HDL_TAP TRUE
J 0
(-5650 4575);
DISPLAY 0.872340 (-5650 4575);
DISPLAY INVISIBLE (-5650 4575);
FORCEPROP 1 LAST PATH I113
J 0
(-5977 4700);
DISPLAY 0.872340 (-5977 4700);
PAINT GREEN (-5977 4700);
DISPLAY INVISIBLE (-5977 4700);
FORCEADD TAP..1
(-5975 4900);
FORCEPROP 3 LASTPIN (-6025 4900) SIG_NAME M_I_CPU1_SA_DQ<22>
J 0
(-6015 4910);
DISPLAY 0.659574 (-6015 4910);
PAINT MONO (-6015 4910);
DISPLAY INVISIBLE (-6015 4910);
FORCEPROP 1 LASTPIN (-6025 4900) BN 22
J 0
(-6037 4908);
DISPLAY 0.489362 (-6037 4908);
PAINT GREEN (-6037 4908);
FORCEPROP 2 LAST CDS_LIB mstr_standard
J 0
(-5975 4900);
DISPLAY 0.723404 (-5975 4900);
PAINT MONO (-5975 4900);
DISPLAY INVISIBLE (-5975 4900);
FORCEPROP 1 LAST BODY_TYPE PLUMBING
J 0
(-5975 4950);
DISPLAY 0.872340 (-5975 4950);
PAINT GREEN (-5975 4950);
DISPLAY INVISIBLE (-5975 4950);
FORCEPROP 1 LAST HDL_TAP TRUE
J 0
(-5650 4775);
DISPLAY 0.872340 (-5650 4775);
DISPLAY INVISIBLE (-5650 4775);
FORCEPROP 1 LAST PATH I114
J 0
(-5977 4900);
DISPLAY 0.872340 (-5977 4900);
PAINT GREEN (-5977 4900);
DISPLAY INVISIBLE (-5977 4900);
FORCEADD TAP..1
(-5975 4850);
FORCEPROP 3 LASTPIN (-6025 4850) SIG_NAME M_I_CPU1_SA_DQ<21>
J 0
(-6015 4860);
DISPLAY 0.659574 (-6015 4860);
PAINT MONO (-6015 4860);
DISPLAY INVISIBLE (-6015 4860);
FORCEPROP 1 LASTPIN (-6025 4850) BN 21
J 0
(-6037 4858);
DISPLAY 0.489362 (-6037 4858);
PAINT GREEN (-6037 4858);
FORCEPROP 2 LAST CDS_LIB mstr_standard
J 0
(-5975 4850);
DISPLAY 0.723404 (-5975 4850);
PAINT MONO (-5975 4850);
DISPLAY INVISIBLE (-5975 4850);
FORCEPROP 1 LAST BODY_TYPE PLUMBING
J 0
(-5975 4900);
DISPLAY 0.872340 (-5975 4900);
PAINT GREEN (-5975 4900);
DISPLAY INVISIBLE (-5975 4900);
FORCEPROP 1 LAST HDL_TAP TRUE
J 0
(-5650 4725);
DISPLAY 0.872340 (-5650 4725);
DISPLAY INVISIBLE (-5650 4725);
FORCEPROP 1 LAST PATH I115
J 0
(-5977 4850);
DISPLAY 0.872340 (-5977 4850);
PAINT GREEN (-5977 4850);
DISPLAY INVISIBLE (-5977 4850);
FORCEADD TAP..1
(-5975 5050);
FORCEPROP 3 LASTPIN (-6025 5050) SIG_NAME M_I_CPU1_SA_DQ<25>
J 0
(-6015 5060);
DISPLAY 0.659574 (-6015 5060);
PAINT MONO (-6015 5060);
DISPLAY INVISIBLE (-6015 5060);
FORCEPROP 1 LASTPIN (-6025 5050) BN 25
J 0
(-6037 5058);
DISPLAY 0.489362 (-6037 5058);
PAINT GREEN (-6037 5058);
FORCEPROP 2 LAST CDS_LIB mstr_standard
J 0
(-5975 5050);
DISPLAY 0.723404 (-5975 5050);
PAINT MONO (-5975 5050);
DISPLAY INVISIBLE (-5975 5050);
FORCEPROP 1 LAST BODY_TYPE PLUMBING
J 0
(-5975 5100);
DISPLAY 0.872340 (-5975 5100);
PAINT GREEN (-5975 5100);
DISPLAY INVISIBLE (-5975 5100);
FORCEPROP 1 LAST HDL_TAP TRUE
J 0
(-5650 4925);
DISPLAY 0.872340 (-5650 4925);
DISPLAY INVISIBLE (-5650 4925);
FORCEPROP 1 LAST PATH I116
J 0
(-5977 5050);
DISPLAY 0.872340 (-5977 5050);
PAINT GREEN (-5977 5050);
DISPLAY INVISIBLE (-5977 5050);
FORCEADD TAP..1
(-5975 5000);
FORCEPROP 3 LASTPIN (-6025 5000) SIG_NAME M_I_CPU1_SA_DQ<24>
J 0
(-6015 5010);
DISPLAY 0.659574 (-6015 5010);
PAINT MONO (-6015 5010);
DISPLAY INVISIBLE (-6015 5010);
FORCEPROP 1 LASTPIN (-6025 5000) BN 24
J 0
(-6037 5008);
DISPLAY 0.489362 (-6037 5008);
PAINT GREEN (-6037 5008);
FORCEPROP 2 LAST CDS_LIB mstr_standard
J 0
(-5975 5000);
DISPLAY 0.723404 (-5975 5000);
PAINT MONO (-5975 5000);
DISPLAY INVISIBLE (-5975 5000);
FORCEPROP 1 LAST BODY_TYPE PLUMBING
J 0
(-5975 5050);
DISPLAY 0.872340 (-5975 5050);
PAINT GREEN (-5975 5050);
DISPLAY INVISIBLE (-5975 5050);
FORCEPROP 1 LAST HDL_TAP TRUE
J 0
(-5650 4875);
DISPLAY 0.872340 (-5650 4875);
DISPLAY INVISIBLE (-5650 4875);
FORCEPROP 1 LAST PATH I117
J 0
(-5977 5000);
DISPLAY 0.872340 (-5977 5000);
PAINT GREEN (-5977 5000);
DISPLAY INVISIBLE (-5977 5000);
FORCEADD TAP..1
(-5975 4950);
FORCEPROP 3 LASTPIN (-6025 4950) SIG_NAME M_I_CPU1_SA_DQ<23>
J 0
(-6015 4960);
DISPLAY 0.659574 (-6015 4960);
PAINT MONO (-6015 4960);
DISPLAY INVISIBLE (-6015 4960);
FORCEPROP 1 LASTPIN (-6025 4950) BN 23
J 0
(-6037 4958);
DISPLAY 0.489362 (-6037 4958);
PAINT GREEN (-6037 4958);
FORCEPROP 2 LAST CDS_LIB mstr_standard
J 0
(-5975 4950);
DISPLAY 0.723404 (-5975 4950);
PAINT MONO (-5975 4950);
DISPLAY INVISIBLE (-5975 4950);
FORCEPROP 1 LAST BODY_TYPE PLUMBING
J 0
(-5975 5000);
DISPLAY 0.872340 (-5975 5000);
PAINT GREEN (-5975 5000);
DISPLAY INVISIBLE (-5975 5000);
FORCEPROP 1 LAST HDL_TAP TRUE
J 0
(-5650 4825);
DISPLAY 0.872340 (-5650 4825);
DISPLAY INVISIBLE (-5650 4825);
FORCEPROP 1 LAST PATH I118
J 0
(-5977 4950);
DISPLAY 0.872340 (-5977 4950);
PAINT GREEN (-5977 4950);
DISPLAY INVISIBLE (-5977 4950);
FORCEADD TAP..1
(-5975 5150);
FORCEPROP 3 LASTPIN (-6025 5150) SIG_NAME M_I_CPU1_SA_DQ<27>
J 0
(-6015 5160);
DISPLAY 0.659574 (-6015 5160);
PAINT MONO (-6015 5160);
DISPLAY INVISIBLE (-6015 5160);
FORCEPROP 1 LASTPIN (-6025 5150) BN 27
J 0
(-6037 5158);
DISPLAY 0.489362 (-6037 5158);
PAINT GREEN (-6037 5158);
FORCEPROP 2 LAST CDS_LIB mstr_standard
J 0
(-5975 5150);
DISPLAY 0.723404 (-5975 5150);
PAINT MONO (-5975 5150);
DISPLAY INVISIBLE (-5975 5150);
FORCEPROP 1 LAST BODY_TYPE PLUMBING
J 0
(-5975 5200);
DISPLAY 0.872340 (-5975 5200);
PAINT GREEN (-5975 5200);
DISPLAY INVISIBLE (-5975 5200);
FORCEPROP 1 LAST HDL_TAP TRUE
J 0
(-5650 5025);
DISPLAY 0.872340 (-5650 5025);
DISPLAY INVISIBLE (-5650 5025);
FORCEPROP 1 LAST PATH I119
J 0
(-5977 5150);
DISPLAY 0.872340 (-5977 5150);
PAINT GREEN (-5977 5150);
DISPLAY INVISIBLE (-5977 5150);
FORCEADD OFFPAGE..1
(-8275 4050);
FORCEPROP 2 LAST $XR0 45 
J 0
(-8526 4050);
DISPLAY 0.638298 (-8526 4050);
PAINT MONO (-8526 4050);
FORCEPROP 2 LAST CDS_LIB mstr_standard
J 0
(-8275 4050);
DISPLAY 0.808511 (-8275 4050);
DISPLAY INVISIBLE (-8275 4050);
FORCEPROP 1 LAST OFFPAGE TRUE
J 0
(-7950 3925);
DISPLAY 0.872340 (-7950 3925);
PAINT GREEN (-7950 3925);
DISPLAY INVISIBLE (-7950 3925);
FORCEPROP 1 LAST COMMENT_BODY TRUE
J 0
(-8150 3950);
DISPLAY 0.872340 (-8150 3950);
PAINT GREEN (-8150 3950);
DISPLAY INVISIBLE (-8150 3950);
FORCEPROP 2 LAST PATH I12
J 0
(-8525 4100);
DISPLAY 1.021277 (-8525 4100);
DISPLAY INVISIBLE (-8525 4100);
FORCEADD TAP..1
(-5975 5200);
FORCEPROP 3 LASTPIN (-6025 5200) SIG_NAME M_I_CPU1_SA_DQ<28>
J 0
(-6015 5210);
DISPLAY 0.659574 (-6015 5210);
PAINT MONO (-6015 5210);
DISPLAY INVISIBLE (-6015 5210);
FORCEPROP 1 LASTPIN (-6025 5200) BN 28
J 0
(-6037 5208);
DISPLAY 0.489362 (-6037 5208);
PAINT GREEN (-6037 5208);
FORCEPROP 2 LAST CDS_LIB mstr_standard
J 0
(-5975 5200);
DISPLAY 0.723404 (-5975 5200);
PAINT MONO (-5975 5200);
DISPLAY INVISIBLE (-5975 5200);
FORCEPROP 1 LAST BODY_TYPE PLUMBING
J 0
(-5975 5250);
DISPLAY 0.872340 (-5975 5250);
PAINT GREEN (-5975 5250);
DISPLAY INVISIBLE (-5975 5250);
FORCEPROP 1 LAST HDL_TAP TRUE
J 0
(-5650 5075);
DISPLAY 0.872340 (-5650 5075);
DISPLAY INVISIBLE (-5650 5075);
FORCEPROP 1 LAST PATH I120
J 0
(-5977 5200);
DISPLAY 0.872340 (-5977 5200);
PAINT GREEN (-5977 5200);
DISPLAY INVISIBLE (-5977 5200);
FORCEADD TAP..1
(-5975 5100);
FORCEPROP 3 LASTPIN (-6025 5100) SIG_NAME M_I_CPU1_SA_DQ<26>
J 0
(-6015 5110);
DISPLAY 0.659574 (-6015 5110);
PAINT MONO (-6015 5110);
DISPLAY INVISIBLE (-6015 5110);
FORCEPROP 1 LASTPIN (-6025 5100) BN 26
J 0
(-6037 5108);
DISPLAY 0.489362 (-6037 5108);
PAINT GREEN (-6037 5108);
FORCEPROP 2 LAST CDS_LIB mstr_standard
J 0
(-5975 5100);
DISPLAY 0.723404 (-5975 5100);
PAINT MONO (-5975 5100);
DISPLAY INVISIBLE (-5975 5100);
FORCEPROP 1 LAST BODY_TYPE PLUMBING
J 0
(-5975 5150);
DISPLAY 0.872340 (-5975 5150);
PAINT GREEN (-5975 5150);
DISPLAY INVISIBLE (-5975 5150);
FORCEPROP 1 LAST HDL_TAP TRUE
J 0
(-5650 4975);
DISPLAY 0.872340 (-5650 4975);
DISPLAY INVISIBLE (-5650 4975);
FORCEPROP 1 LAST PATH I121
J 0
(-5977 5100);
DISPLAY 0.872340 (-5977 5100);
PAINT GREEN (-5977 5100);
DISPLAY INVISIBLE (-5977 5100);
FORCEADD TAP..1
(-5975 5300);
FORCEPROP 3 LASTPIN (-6025 5300) SIG_NAME M_I_CPU1_SA_DQ<30>
J 0
(-6015 5310);
DISPLAY 0.659574 (-6015 5310);
PAINT MONO (-6015 5310);
DISPLAY INVISIBLE (-6015 5310);
FORCEPROP 1 LASTPIN (-6025 5300) BN 30
J 0
(-6037 5308);
DISPLAY 0.489362 (-6037 5308);
PAINT GREEN (-6037 5308);
FORCEPROP 2 LAST CDS_LIB mstr_standard
J 0
(-5975 5300);
DISPLAY 0.723404 (-5975 5300);
PAINT MONO (-5975 5300);
DISPLAY INVISIBLE (-5975 5300);
FORCEPROP 1 LAST BODY_TYPE PLUMBING
J 0
(-5975 5350);
DISPLAY 0.872340 (-5975 5350);
PAINT GREEN (-5975 5350);
DISPLAY INVISIBLE (-5975 5350);
FORCEPROP 1 LAST HDL_TAP TRUE
J 0
(-5650 5175);
DISPLAY 0.872340 (-5650 5175);
DISPLAY INVISIBLE (-5650 5175);
FORCEPROP 1 LAST PATH I122
J 0
(-5977 5300);
DISPLAY 0.872340 (-5977 5300);
PAINT GREEN (-5977 5300);
DISPLAY INVISIBLE (-5977 5300);
FORCEADD TAP..1
(-5975 5250);
FORCEPROP 3 LASTPIN (-6025 5250) SIG_NAME M_I_CPU1_SA_DQ<29>
J 0
(-6015 5260);
DISPLAY 0.659574 (-6015 5260);
PAINT MONO (-6015 5260);
DISPLAY INVISIBLE (-6015 5260);
FORCEPROP 1 LASTPIN (-6025 5250) BN 29
J 0
(-6037 5258);
DISPLAY 0.489362 (-6037 5258);
PAINT GREEN (-6037 5258);
FORCEPROP 2 LAST CDS_LIB mstr_standard
J 0
(-5975 5250);
DISPLAY 0.723404 (-5975 5250);
PAINT MONO (-5975 5250);
DISPLAY INVISIBLE (-5975 5250);
FORCEPROP 1 LAST BODY_TYPE PLUMBING
J 0
(-5975 5300);
DISPLAY 0.872340 (-5975 5300);
PAINT GREEN (-5975 5300);
DISPLAY INVISIBLE (-5975 5300);
FORCEPROP 1 LAST HDL_TAP TRUE
J 0
(-5650 5125);
DISPLAY 0.872340 (-5650 5125);
DISPLAY INVISIBLE (-5650 5125);
FORCEPROP 1 LAST PATH I123
J 0
(-5977 5250);
DISPLAY 0.872340 (-5977 5250);
PAINT GREEN (-5977 5250);
DISPLAY INVISIBLE (-5977 5250);
FORCEADD TAP..1
(-5975 5350);
FORCEPROP 3 LASTPIN (-6025 5350) SIG_NAME M_I_CPU1_SA_DQ<31>
J 0
(-6015 5360);
DISPLAY 0.659574 (-6015 5360);
PAINT MONO (-6015 5360);
DISPLAY INVISIBLE (-6015 5360);
FORCEPROP 1 LASTPIN (-6025 5350) BN 31
J 0
(-6037 5358);
DISPLAY 0.489362 (-6037 5358);
PAINT GREEN (-6037 5358);
FORCEPROP 2 LAST CDS_LIB mstr_standard
J 0
(-5975 5350);
DISPLAY 0.723404 (-5975 5350);
PAINT MONO (-5975 5350);
DISPLAY INVISIBLE (-5975 5350);
FORCEPROP 1 LAST BODY_TYPE PLUMBING
J 0
(-5975 5400);
DISPLAY 0.872340 (-5975 5400);
PAINT GREEN (-5975 5400);
DISPLAY INVISIBLE (-5975 5400);
FORCEPROP 1 LAST HDL_TAP TRUE
J 0
(-5650 5225);
DISPLAY 0.872340 (-5650 5225);
DISPLAY INVISIBLE (-5650 5225);
FORCEPROP 1 LAST PATH I124
J 0
(-5977 5350);
DISPLAY 0.872340 (-5977 5350);
PAINT GREEN (-5977 5350);
DISPLAY INVISIBLE (-5977 5350);
FORCEADD OFFPAGE..3
(-5275 5400);
FORCEPROP 2 LAST $XR0 45 
J 0
(-5061 5400);
DISPLAY 0.638298 (-5061 5400);
PAINT MONO (-5061 5400);
FORCEPROP 2 LAST CDS_LIB mstr_standard
J 0
(-5275 5400);
DISPLAY 0.723404 (-5275 5400);
PAINT MONO (-5275 5400);
DISPLAY INVISIBLE (-5275 5400);
FORCEPROP 1 LAST OFFPAGE TRUE
J 0
(-4950 5275);
DISPLAY 0.872340 (-4950 5275);
PAINT GREEN (-4950 5275);
DISPLAY INVISIBLE (-4950 5275);
FORCEPROP 1 LAST COMMENT_BODY TRUE
J 0
(-5325 5300);
DISPLAY 0.872340 (-5325 5300);
PAINT GREEN (-5325 5300);
DISPLAY INVISIBLE (-5325 5300);
FORCEPROP 2 LAST PATH I125
J 0
(-5050 5450);
DISPLAY 1.021277 (-5050 5450);
DISPLAY INVISIBLE (-5050 5450);
FORCEADD OFFPAGE..5
(-7150 1325);
FORCEPROP 2 LAST $XR0 106 
J 0
(-7405 1325);
DISPLAY 0.638298 (-7405 1325);
PAINT MONO (-7405 1325);
FORCEPROP 2 LAST BOM_COST MEM
J 0
(-7225 1400);
DISPLAY 0.808511 (-7225 1400);
DISPLAY INVISIBLE (-7225 1400);
FORCEPROP 2 LAST CDS_LIB mstr_standard
J 0
(-7150 1325);
DISPLAY 0.808511 (-7150 1325);
DISPLAY INVISIBLE (-7150 1325);
FORCEPROP 1 LAST OFFPAGE TRUE
J 0
(-6825 1200);
DISPLAY 0.872340 (-6825 1200);
PAINT GREEN (-6825 1200);
DISPLAY INVISIBLE (-6825 1200);
FORCEPROP 1 LAST COMMENT_BODY TRUE
J 0
(-7050 1250);
DISPLAY 0.872340 (-7050 1250);
PAINT GREEN (-7050 1250);
DISPLAY INVISIBLE (-7050 1250);
FORCEPROP 2 LAST PATH I126
J 0
(-7425 1375);
DISPLAY 1.021277 (-7425 1375);
DISPLAY INVISIBLE (-7425 1375);
FORCEADD GND..1
(-6375 925);
FORCEPROP 3 LASTPIN (-6375 975) SIG_NAME GND\g
J 0
(-6365 985);
DISPLAY 0.659574 (-6365 985);
PAINT MONO (-6365 985);
DISPLAY INVISIBLE (-6365 985);
FORCEPROP 1 LAST SIZE 1B
J 0
(-6300 875);
DISPLAY 0.851064 (-6300 875);
PAINT GREEN (-6300 875);
DISPLAY INVISIBLE (-6300 875);
FORCEPROP 2 LAST CDS_LIB mstr_symbols
J 0
(-6375 925);
DISPLAY 0.808511 (-6375 925);
DISPLAY INVISIBLE (-6375 925);
FORCEPROP 2 LAST BOM_COST MEM
J 0
(-6475 1000);
DISPLAY 0.808511 (-6475 1000);
DISPLAY INVISIBLE (-6475 1000);
FORCEPROP 1 LAST VOLTAGE 0.0
J 0
(-6420 882);
DISPLAY 0.723404 (-6420 882);
PAINT SKYBLUE (-6420 882);
DISPLAY INVISIBLE (-6420 882);
FORCEPROP 1 LAST BODY_TYPE PLUMBING
J 0
(-6420 882);
DISPLAY 0.340426 (-6420 882);
PAINT GREEN (-6420 882);
DISPLAY INVISIBLE (-6420 882);
FORCEPROP 1 LAST HDL_POWER GND
J 0
(-6375 1075);
DISPLAY 0.851064 (-6375 1075);
PAINT GREEN (-6375 1075);
DISPLAY INVISIBLE (-6375 1075);
FORCEPROP 1 LAST PATH I127
J 0
(-6300 925);
DISPLAY 0.872340 (-6300 925);
PAINT AQUA (-6300 925);
DISPLAY INVISIBLE (-6300 925);
FORCEADD Q_RES..2
(-6375 1150);
FORCEPROP 1 LAST LOCATION R775
J 0
(-6330 1275);
DISPLAY 0.489362 (-6330 1275);
PAINT SKYBLUE (-6330 1275);
FORCEPROP 0 LAST $SEC 1
J 0
(-6325 1325);
DISPLAY 0.680851 (-6325 1325);
PAINT MONO (-6325 1325);
DISPLAY INVISIBLE (-6325 1325);
FORCEPROP 0 LAST CDS_SEC 1
J 0
(-6325 1325);
DISPLAY 1.021277 (-6325 1325);
DISPLAY INVISIBLE (-6325 1325);
FORCEPROP 1 LASTPIN (-6375 1250) $PN 1
J 0
(-6370 1212);
DISPLAY 0.489362 (-6370 1212);
PAINT MONO (-6370 1212);
FORCEPROP 1 LASTPIN (-6375 1050) $PN 2
J 0
(-6370 1060);
DISPLAY 0.489362 (-6370 1060);
PAINT MONO (-6370 1060);
FORCEPROP 1 LAST PACK_TYPE 0402LF
J 0
(-6335 975);
DISPLAY 0.489362 (-6335 975);
PAINT SKYBLUE (-6335 975);
FORCEPROP 1 LAST VALUE 23.2K
J 0
(-6330 1225);
DISPLAY 0.489362 (-6330 1225);
PAINT SKYBLUE (-6330 1225);
FORCEPROP 1 LAST TOLERANCE 1%
J 0
(-6330 1175);
DISPLAY 0.489362 (-6330 1175);
PAINT SKYBLUE (-6330 1175);
FORCEPROP 1 LAST MATERIAL CHIP
J 0
(-6335 1075);
DISPLAY 0.489362 (-6335 1075);
PAINT SKYBLUE (-6335 1075);
FORCEPROP 1 LAST WATTAGE 1/16W
J 0
(-6335 1125);
DISPLAY 0.489362 (-6335 1125);
PAINT SKYBLUE (-6335 1125);
FORCEPROP 2 LAST CDS_LIB pure_quanta
J 0
(-6375 1150);
DISPLAY INVISIBLE (-6375 1150);
FORCEPROP 1 LAST PATH I128
J 0
(-6325 1325);
DISPLAY 0.978723 (-6325 1325);
PAINT WHITE (-6325 1325);
DISPLAY INVISIBLE (-6325 1325);
FORCEPROP 1 LAST PART_NUMBER CS32322FB03
J 0
(-6335 1025);
DISPLAY 0.489362 (-6335 1025);
PAINT SKYBLUE (-6335 1025);
DISPLAY INVISIBLE (-6335 1025);
FORCEADD OFFPAGE..1
(-8275 4250);
FORCEPROP 2 LAST $XR0 45 
J 0
(-8526 4250);
DISPLAY 0.638298 (-8526 4250);
PAINT MONO (-8526 4250);
FORCEPROP 2 LAST CDS_LIB mstr_standard
J 0
(-8275 4250);
DISPLAY 0.723404 (-8275 4250);
PAINT MONO (-8275 4250);
DISPLAY INVISIBLE (-8275 4250);
FORCEPROP 1 LAST OFFPAGE TRUE
J 0
(-7950 4125);
DISPLAY 0.872340 (-7950 4125);
PAINT GREEN (-7950 4125);
DISPLAY INVISIBLE (-7950 4125);
FORCEPROP 1 LAST COMMENT_BODY TRUE
J 0
(-8150 4150);
DISPLAY 0.872340 (-8150 4150);
PAINT GREEN (-8150 4150);
DISPLAY INVISIBLE (-8150 4150);
FORCEPROP 2 LAST PATH I13
J 0
(-8525 4300);
DISPLAY 1.021277 (-8525 4300);
DISPLAY INVISIBLE (-8525 4300);
FORCEADD OFFPAGE..1
(-8275 4200);
FORCEPROP 2 LAST $XR0 45 
J 0
(-8526 4200);
DISPLAY 0.638298 (-8526 4200);
PAINT MONO (-8526 4200);
FORCEPROP 2 LAST CDS_LIB mstr_standard
J 0
(-8275 4200);
DISPLAY 0.808511 (-8275 4200);
DISPLAY INVISIBLE (-8275 4200);
FORCEPROP 1 LAST OFFPAGE TRUE
J 0
(-7950 4075);
DISPLAY 0.872340 (-7950 4075);
PAINT GREEN (-7950 4075);
DISPLAY INVISIBLE (-7950 4075);
FORCEPROP 1 LAST COMMENT_BODY TRUE
J 0
(-8150 4100);
DISPLAY 0.872340 (-8150 4100);
PAINT GREEN (-8150 4100);
DISPLAY INVISIBLE (-8150 4100);
FORCEPROP 2 LAST PATH I14
J 0
(-8525 4250);
DISPLAY 1.021277 (-8525 4250);
DISPLAY INVISIBLE (-8525 4250);
FORCEADD GND..1
(-2125 1825);
FORCEPROP 3 LASTPIN (-2125 1875) SIG_NAME GND\g
J 0
(-2115 1885);
DISPLAY 0.659574 (-2115 1885);
PAINT MONO (-2115 1885);
DISPLAY INVISIBLE (-2115 1885);
FORCEPROP 1 LAST SIZE 1B
J 0
(-2050 1775);
DISPLAY 0.851064 (-2050 1775);
PAINT GREEN (-2050 1775);
DISPLAY INVISIBLE (-2050 1775);
FORCEPROP 2 LAST CDS_LIB mstr_symbols
J 0
(-2125 1825);
DISPLAY 0.723404 (-2125 1825);
DISPLAY INVISIBLE (-2125 1825);
FORCEPROP 1 LAST VOLTAGE 0.0
J 0
(-2170 1782);
DISPLAY 0.723404 (-2170 1782);
PAINT SKYBLUE (-2170 1782);
DISPLAY INVISIBLE (-2170 1782);
FORCEPROP 1 LAST BODY_TYPE PLUMBING
J 0
(-2170 1782);
DISPLAY 0.340426 (-2170 1782);
PAINT GREEN (-2170 1782);
DISPLAY INVISIBLE (-2170 1782);
FORCEPROP 1 LAST HDL_POWER GND
J 0
(-2125 1975);
DISPLAY 0.851064 (-2125 1975);
PAINT GREEN (-2125 1975);
DISPLAY INVISIBLE (-2125 1975);
FORCEPROP 1 LAST PATH I140
J 0
(-2050 1825);
DISPLAY 0.872340 (-2050 1825);
PAINT AQUA (-2050 1825);
DISPLAY INVISIBLE (-2050 1825);
FORCEADD GND..1
(-325 1600);
FORCEPROP 3 LASTPIN (-325 1650) SIG_NAME GND\g
J 0
(-315 1660);
DISPLAY 0.659574 (-315 1660);
PAINT MONO (-315 1660);
DISPLAY INVISIBLE (-315 1660);
FORCEPROP 1 LAST SIZE 1B
J 0
(-250 1550);
DISPLAY 0.851064 (-250 1550);
PAINT GREEN (-250 1550);
DISPLAY INVISIBLE (-250 1550);
FORCEPROP 2 LAST CDS_LIB mstr_symbols
J 0
(-325 1600);
DISPLAY 0.723404 (-325 1600);
DISPLAY INVISIBLE (-325 1600);
FORCEPROP 1 LAST VOLTAGE 0.0
J 0
(-370 1557);
DISPLAY 0.723404 (-370 1557);
PAINT SKYBLUE (-370 1557);
DISPLAY INVISIBLE (-370 1557);
FORCEPROP 1 LAST BODY_TYPE PLUMBING
J 0
(-370 1557);
DISPLAY 0.340426 (-370 1557);
PAINT GREEN (-370 1557);
DISPLAY INVISIBLE (-370 1557);
FORCEPROP 1 LAST HDL_POWER GND
J 0
(-325 1750);
DISPLAY 0.851064 (-325 1750);
PAINT GREEN (-325 1750);
DISPLAY INVISIBLE (-325 1750);
FORCEPROP 1 LAST PATH I141
J 0
(-250 1600);
DISPLAY 0.872340 (-250 1600);
PAINT AQUA (-250 1600);
DISPLAY INVISIBLE (-250 1600);
FORCEADD OFFPAGE..1
(-8275 4100);
FORCEPROP 2 LAST $XR0 45 
J 0
(-8526 4100);
DISPLAY 0.638298 (-8526 4100);
PAINT MONO (-8526 4100);
FORCEPROP 2 LAST CDS_LIB mstr_standard
J 0
(-8275 4100);
DISPLAY 0.723404 (-8275 4100);
PAINT MONO (-8275 4100);
DISPLAY INVISIBLE (-8275 4100);
FORCEPROP 1 LAST OFFPAGE TRUE
J 0
(-7950 3975);
DISPLAY 0.872340 (-7950 3975);
PAINT GREEN (-7950 3975);
DISPLAY INVISIBLE (-7950 3975);
FORCEPROP 1 LAST COMMENT_BODY TRUE
J 0
(-8150 4000);
DISPLAY 0.872340 (-8150 4000);
PAINT GREEN (-8150 4000);
DISPLAY INVISIBLE (-8150 4000);
FORCEPROP 2 LAST PATH I15
J 0
(-8525 4150);
DISPLAY 1.021277 (-8525 4150);
DISPLAY INVISIBLE (-8525 4150);
FORCEADD OFFPAGE..1
(-8275 4350);
FORCEPROP 2 LAST $XR0 45 
J 0
(-8526 4350);
DISPLAY 0.638298 (-8526 4350);
PAINT MONO (-8526 4350);
FORCEPROP 2 LAST CDS_LIB mstr_standard
J 0
(-8275 4350);
DISPLAY 0.808511 (-8275 4350);
DISPLAY INVISIBLE (-8275 4350);
FORCEPROP 1 LAST OFFPAGE TRUE
J 0
(-7950 4225);
DISPLAY 0.872340 (-7950 4225);
PAINT GREEN (-7950 4225);
DISPLAY INVISIBLE (-7950 4225);
FORCEPROP 1 LAST COMMENT_BODY TRUE
J 0
(-8150 4250);
DISPLAY 0.872340 (-8150 4250);
PAINT GREEN (-8150 4250);
DISPLAY INVISIBLE (-8150 4250);
FORCEPROP 2 LAST PATH I16
J 0
(-8525 4400);
DISPLAY 1.021277 (-8525 4400);
DISPLAY INVISIBLE (-8525 4400);
FORCEADD OFFPAGE..1
(-8275 4500);
FORCEPROP 2 LAST $XR0 45 
J 0
(-8526 4500);
DISPLAY 0.638298 (-8526 4500);
PAINT MONO (-8526 4500);
FORCEPROP 2 LAST CDS_LIB mstr_standard
J 0
(-8275 4500);
DISPLAY 0.808511 (-8275 4500);
DISPLAY INVISIBLE (-8275 4500);
FORCEPROP 1 LAST OFFPAGE TRUE
J 0
(-7950 4375);
DISPLAY 0.872340 (-7950 4375);
PAINT GREEN (-7950 4375);
DISPLAY INVISIBLE (-7950 4375);
FORCEPROP 1 LAST COMMENT_BODY TRUE
J 0
(-8150 4400);
DISPLAY 0.872340 (-8150 4400);
PAINT GREEN (-8150 4400);
DISPLAY INVISIBLE (-8150 4400);
FORCEPROP 2 LAST PATH I17
J 0
(-8525 4550);
DISPLAY 1.021277 (-8525 4550);
DISPLAY INVISIBLE (-8525 4550);
FORCEADD SCONN288_DDR506112002KQ..3
(-1225 3600);
FORCEPROP 1 LAST LOCATION J100
J 0
(-1675 5575);
DISPLAY 0.468085 (-1675 5575);
PAINT SKYBLUE (-1675 5575);
FORCEPROP 0 LAST $SEC 3
J 0
(-1675 5725);
DISPLAY 0.680851 (-1675 5725);
PAINT MONO (-1675 5725);
DISPLAY INVISIBLE (-1675 5725);
FORCEPROP 2 LAST CDS_SEC 3
J 0
(-1675 5725);
DISPLAY 1.021277 (-1675 5725);
DISPLAY INVISIBLE (-1675 5725);
FORCEPROP 0 LASTPIN (-625 2000) $PN G1
J 0
(-615 2010);
DISPLAY 0.680851 (-615 2010);
PAINT MONO (-615 2010);
FORCEPROP 0 LASTPIN (-625 1950) $PN G2
J 0
(-615 1960);
DISPLAY 0.680851 (-615 1960);
PAINT MONO (-615 1960);
FORCEPROP 0 LASTPIN (-625 1900) $PN G3
J 0
(-615 1910);
DISPLAY 0.680851 (-615 1910);
PAINT MONO (-615 1910);
FORCEPROP 0 LASTPIN (-1825 5150) $PN 1
J 2
(-1835 5160);
DISPLAY 0.680851 (-1835 5160);
PAINT MONO (-1835 5160);
FORCEPROP 0 LASTPIN (-1825 5200) $PN 145
J 2
(-1835 5210);
DISPLAY 0.680851 (-1835 5210);
PAINT MONO (-1835 5210);
FORCEPROP 0 LASTPIN (-1825 5250) $PN 146
J 2
(-1835 5260);
DISPLAY 0.680851 (-1835 5260);
PAINT MONO (-1835 5260);
FORCEPROP 0 LASTPIN (-625 2100) $PN 6
J 0
(-615 2110);
DISPLAY 0.680851 (-615 2110);
PAINT MONO (-615 2110);
FORCEPROP 0 LASTPIN (-625 2150) $PN 8
J 0
(-615 2160);
DISPLAY 0.680851 (-615 2160);
PAINT MONO (-615 2160);
FORCEPROP 0 LASTPIN (-625 2200) $PN 10
J 0
(-615 2210);
DISPLAY 0.680851 (-615 2210);
PAINT MONO (-615 2210);
FORCEPROP 0 LASTPIN (-625 2250) $PN 13
J 0
(-615 2260);
DISPLAY 0.680851 (-615 2260);
PAINT MONO (-615 2260);
FORCEPROP 0 LASTPIN (-625 2300) $PN 15
J 0
(-615 2310);
DISPLAY 0.680851 (-615 2310);
PAINT MONO (-615 2310);
FORCEPROP 0 LASTPIN (-625 2350) $PN 17
J 0
(-615 2360);
DISPLAY 0.680851 (-615 2360);
PAINT MONO (-615 2360);
FORCEPROP 0 LASTPIN (-625 2400) $PN 19
J 0
(-615 2410);
DISPLAY 0.680851 (-615 2410);
PAINT MONO (-615 2410);
FORCEPROP 0 LASTPIN (-625 2450) $PN 21
J 0
(-615 2460);
DISPLAY 0.680851 (-615 2460);
PAINT MONO (-615 2460);
FORCEPROP 0 LASTPIN (-625 2500) $PN 24
J 0
(-615 2510);
DISPLAY 0.680851 (-615 2510);
PAINT MONO (-615 2510);
FORCEPROP 0 LASTPIN (-625 2550) $PN 26
J 0
(-615 2560);
DISPLAY 0.680851 (-615 2560);
PAINT MONO (-615 2560);
FORCEPROP 0 LASTPIN (-625 2600) $PN 28
J 0
(-615 2610);
DISPLAY 0.680851 (-615 2610);
PAINT MONO (-615 2610);
FORCEPROP 0 LASTPIN (-625 2650) $PN 30
J 0
(-615 2660);
DISPLAY 0.680851 (-615 2660);
PAINT MONO (-615 2660);
FORCEPROP 0 LASTPIN (-625 2700) $PN 32
J 0
(-615 2710);
DISPLAY 0.680851 (-615 2710);
PAINT MONO (-615 2710);
FORCEPROP 0 LASTPIN (-625 2750) $PN 35
J 0
(-615 2760);
DISPLAY 0.680851 (-615 2760);
PAINT MONO (-615 2760);
FORCEPROP 0 LASTPIN (-625 2800) $PN 37
J 0
(-615 2810);
DISPLAY 0.680851 (-615 2810);
PAINT MONO (-615 2810);
FORCEPROP 0 LASTPIN (-625 2850) $PN 39
J 0
(-615 2860);
DISPLAY 0.680851 (-615 2860);
PAINT MONO (-615 2860);
FORCEPROP 0 LASTPIN (-625 2900) $PN 41
J 0
(-615 2910);
DISPLAY 0.680851 (-615 2910);
PAINT MONO (-615 2910);
FORCEPROP 0 LASTPIN (-625 2950) $PN 43
J 0
(-615 2960);
DISPLAY 0.680851 (-615 2960);
PAINT MONO (-615 2960);
FORCEPROP 0 LASTPIN (-625 3000) $PN 46
J 0
(-615 3010);
DISPLAY 0.680851 (-615 3010);
PAINT MONO (-615 3010);
FORCEPROP 0 LASTPIN (-625 3050) $PN 48
J 0
(-615 3060);
DISPLAY 0.680851 (-615 3060);
PAINT MONO (-615 3060);
FORCEPROP 0 LASTPIN (-625 3100) $PN 50
J 0
(-615 3110);
DISPLAY 0.680851 (-615 3110);
PAINT MONO (-615 3110);
FORCEPROP 0 LASTPIN (-625 3150) $PN 52
J 0
(-615 3160);
DISPLAY 0.680851 (-615 3160);
PAINT MONO (-615 3160);
FORCEPROP 0 LASTPIN (-625 3200) $PN 54
J 0
(-615 3210);
DISPLAY 0.680851 (-615 3210);
PAINT MONO (-615 3210);
FORCEPROP 0 LASTPIN (-625 3250) $PN 57
J 0
(-615 3260);
DISPLAY 0.680851 (-615 3260);
PAINT MONO (-615 3260);
FORCEPROP 0 LASTPIN (-625 3300) $PN 59
J 0
(-615 3310);
DISPLAY 0.680851 (-615 3310);
PAINT MONO (-615 3310);
FORCEPROP 0 LASTPIN (-625 3350) $PN 61
J 0
(-615 3360);
DISPLAY 0.680851 (-615 3360);
PAINT MONO (-615 3360);
FORCEPROP 0 LASTPIN (-625 3400) $PN 63
J 0
(-615 3410);
DISPLAY 0.680851 (-615 3410);
PAINT MONO (-615 3410);
FORCEPROP 0 LASTPIN (-625 3450) $PN 65
J 0
(-615 3460);
DISPLAY 0.680851 (-615 3460);
PAINT MONO (-615 3460);
FORCEPROP 0 LASTPIN (-625 3500) $PN 67
J 0
(-615 3510);
DISPLAY 0.680851 (-615 3510);
PAINT MONO (-615 3510);
FORCEPROP 0 LASTPIN (-625 3550) $PN 69
J 0
(-615 3560);
DISPLAY 0.680851 (-615 3560);
PAINT MONO (-615 3560);
FORCEPROP 0 LASTPIN (-625 3600) $PN 71
J 0
(-615 3610);
DISPLAY 0.680851 (-615 3610);
PAINT MONO (-615 3610);
FORCEPROP 0 LASTPIN (-625 3650) $PN 73
J 0
(-615 3660);
DISPLAY 0.680851 (-615 3660);
PAINT MONO (-615 3660);
FORCEPROP 0 LASTPIN (-625 3700) $PN 75
J 0
(-615 3710);
DISPLAY 0.680851 (-615 3710);
PAINT MONO (-615 3710);
FORCEPROP 0 LASTPIN (-625 3750) $PN 77
J 0
(-615 3760);
DISPLAY 0.680851 (-615 3760);
PAINT MONO (-615 3760);
FORCEPROP 0 LASTPIN (-625 3800) $PN 79
J 0
(-615 3810);
DISPLAY 0.680851 (-615 3810);
PAINT MONO (-615 3810);
FORCEPROP 0 LASTPIN (-625 3850) $PN 81
J 0
(-615 3860);
DISPLAY 0.680851 (-615 3860);
PAINT MONO (-615 3860);
FORCEPROP 0 LASTPIN (-625 3900) $PN 83
J 0
(-615 3910);
DISPLAY 0.680851 (-615 3910);
PAINT MONO (-615 3910);
FORCEPROP 0 LASTPIN (-625 3950) $PN 85
J 0
(-615 3960);
DISPLAY 0.680851 (-615 3960);
PAINT MONO (-615 3960);
FORCEPROP 0 LASTPIN (-625 4000) $PN 88
J 0
(-615 4010);
DISPLAY 0.680851 (-615 4010);
PAINT MONO (-615 4010);
FORCEPROP 0 LASTPIN (-625 4050) $PN 90
J 0
(-615 4060);
DISPLAY 0.680851 (-615 4060);
PAINT MONO (-615 4060);
FORCEPROP 0 LASTPIN (-625 4100) $PN 92
J 0
(-615 4110);
DISPLAY 0.680851 (-615 4110);
PAINT MONO (-615 4110);
FORCEPROP 0 LASTPIN (-625 4150) $PN 95
J 0
(-615 4160);
DISPLAY 0.680851 (-615 4160);
PAINT MONO (-615 4160);
FORCEPROP 0 LASTPIN (-625 4200) $PN 97
J 0
(-615 4210);
DISPLAY 0.680851 (-615 4210);
PAINT MONO (-615 4210);
FORCEPROP 0 LASTPIN (-625 4250) $PN 99
J 0
(-615 4260);
DISPLAY 0.680851 (-615 4260);
PAINT MONO (-615 4260);
FORCEPROP 0 LASTPIN (-625 4300) $PN 101
J 0
(-615 4310);
DISPLAY 0.680851 (-615 4310);
PAINT MONO (-615 4310);
FORCEPROP 0 LASTPIN (-625 4350) $PN 103
J 0
(-615 4360);
DISPLAY 0.680851 (-615 4360);
PAINT MONO (-615 4360);
FORCEPROP 0 LASTPIN (-625 4400) $PN 106
J 0
(-615 4410);
DISPLAY 0.680851 (-615 4410);
PAINT MONO (-615 4410);
FORCEPROP 0 LASTPIN (-625 4450) $PN 108
J 0
(-615 4460);
DISPLAY 0.680851 (-615 4460);
PAINT MONO (-615 4460);
FORCEPROP 0 LASTPIN (-625 4500) $PN 110
J 0
(-615 4510);
DISPLAY 0.680851 (-615 4510);
PAINT MONO (-615 4510);
FORCEPROP 0 LASTPIN (-625 4550) $PN 112
J 0
(-615 4560);
DISPLAY 0.680851 (-615 4560);
PAINT MONO (-615 4560);
FORCEPROP 0 LASTPIN (-625 4600) $PN 114
J 0
(-615 4610);
DISPLAY 0.680851 (-615 4610);
PAINT MONO (-615 4610);
FORCEPROP 0 LASTPIN (-625 4650) $PN 117
J 0
(-615 4660);
DISPLAY 0.680851 (-615 4660);
PAINT MONO (-615 4660);
FORCEPROP 0 LASTPIN (-625 4700) $PN 119
J 0
(-615 4710);
DISPLAY 0.680851 (-615 4710);
PAINT MONO (-615 4710);
FORCEPROP 0 LASTPIN (-625 4750) $PN 121
J 0
(-615 4760);
DISPLAY 0.680851 (-615 4760);
PAINT MONO (-615 4760);
FORCEPROP 0 LASTPIN (-625 4800) $PN 123
J 0
(-615 4810);
DISPLAY 0.680851 (-615 4810);
PAINT MONO (-615 4810);
FORCEPROP 0 LASTPIN (-625 4850) $PN 125
J 0
(-615 4860);
DISPLAY 0.680851 (-615 4860);
PAINT MONO (-615 4860);
FORCEPROP 0 LASTPIN (-625 4900) $PN 128
J 0
(-615 4910);
DISPLAY 0.680851 (-615 4910);
PAINT MONO (-615 4910);
FORCEPROP 0 LASTPIN (-625 4950) $PN 130
J 0
(-615 4960);
DISPLAY 0.680851 (-615 4960);
PAINT MONO (-615 4960);
FORCEPROP 0 LASTPIN (-625 5000) $PN 132
J 0
(-615 5010);
DISPLAY 0.680851 (-615 5010);
PAINT MONO (-615 5010);
FORCEPROP 0 LASTPIN (-625 5050) $PN 134
J 0
(-615 5060);
DISPLAY 0.680851 (-615 5060);
PAINT MONO (-615 5060);
FORCEPROP 0 LASTPIN (-625 5100) $PN 136
J 0
(-615 5110);
DISPLAY 0.680851 (-615 5110);
PAINT MONO (-615 5110);
FORCEPROP 0 LASTPIN (-625 5150) $PN 139
J 0
(-615 5160);
DISPLAY 0.680851 (-615 5160);
PAINT MONO (-615 5160);
FORCEPROP 0 LASTPIN (-625 5200) $PN 141
J 0
(-615 5210);
DISPLAY 0.680851 (-615 5210);
PAINT MONO (-615 5210);
FORCEPROP 0 LASTPIN (-625 5250) $PN 143
J 0
(-615 5260);
DISPLAY 0.680851 (-615 5260);
PAINT MONO (-615 5260);
FORCEPROP 0 LASTPIN (-1825 2000) $PN 151
J 2
(-1835 2010);
DISPLAY 0.680851 (-1835 2010);
PAINT MONO (-1835 2010);
FORCEPROP 0 LASTPIN (-1825 2050) $PN 153
J 2
(-1835 2060);
DISPLAY 0.680851 (-1835 2060);
PAINT MONO (-1835 2060);
FORCEPROP 0 LASTPIN (-1825 2100) $PN 155
J 2
(-1835 2110);
DISPLAY 0.680851 (-1835 2110);
PAINT MONO (-1835 2110);
FORCEPROP 0 LASTPIN (-1825 2150) $PN 158
J 2
(-1835 2160);
DISPLAY 0.680851 (-1835 2160);
PAINT MONO (-1835 2160);
FORCEPROP 0 LASTPIN (-1825 2200) $PN 160
J 2
(-1835 2210);
DISPLAY 0.680851 (-1835 2210);
PAINT MONO (-1835 2210);
FORCEPROP 0 LASTPIN (-1825 2250) $PN 162
J 2
(-1835 2260);
DISPLAY 0.680851 (-1835 2260);
PAINT MONO (-1835 2260);
FORCEPROP 0 LASTPIN (-1825 2300) $PN 164
J 2
(-1835 2310);
DISPLAY 0.680851 (-1835 2310);
PAINT MONO (-1835 2310);
FORCEPROP 0 LASTPIN (-1825 2350) $PN 166
J 2
(-1835 2360);
DISPLAY 0.680851 (-1835 2360);
PAINT MONO (-1835 2360);
FORCEPROP 0 LASTPIN (-1825 2400) $PN 169
J 2
(-1835 2410);
DISPLAY 0.680851 (-1835 2410);
PAINT MONO (-1835 2410);
FORCEPROP 0 LASTPIN (-1825 2450) $PN 171
J 2
(-1835 2460);
DISPLAY 0.680851 (-1835 2460);
PAINT MONO (-1835 2460);
FORCEPROP 0 LASTPIN (-1825 2500) $PN 173
J 2
(-1835 2510);
DISPLAY 0.680851 (-1835 2510);
PAINT MONO (-1835 2510);
FORCEPROP 0 LASTPIN (-1825 2550) $PN 175
J 2
(-1835 2560);
DISPLAY 0.680851 (-1835 2560);
PAINT MONO (-1835 2560);
FORCEPROP 0 LASTPIN (-1825 2600) $PN 177
J 2
(-1835 2610);
DISPLAY 0.680851 (-1835 2610);
PAINT MONO (-1835 2610);
FORCEPROP 0 LASTPIN (-1825 2650) $PN 180
J 2
(-1835 2660);
DISPLAY 0.680851 (-1835 2660);
PAINT MONO (-1835 2660);
FORCEPROP 0 LASTPIN (-1825 2700) $PN 182
J 2
(-1835 2710);
DISPLAY 0.680851 (-1835 2710);
PAINT MONO (-1835 2710);
FORCEPROP 0 LASTPIN (-1825 2750) $PN 184
J 2
(-1835 2760);
DISPLAY 0.680851 (-1835 2760);
PAINT MONO (-1835 2760);
FORCEPROP 0 LASTPIN (-1825 2800) $PN 186
J 2
(-1835 2810);
DISPLAY 0.680851 (-1835 2810);
PAINT MONO (-1835 2810);
FORCEPROP 0 LASTPIN (-1825 2850) $PN 188
J 2
(-1835 2860);
DISPLAY 0.680851 (-1835 2860);
PAINT MONO (-1835 2860);
FORCEPROP 0 LASTPIN (-1825 2900) $PN 191
J 2
(-1835 2910);
DISPLAY 0.680851 (-1835 2910);
PAINT MONO (-1835 2910);
FORCEPROP 0 LASTPIN (-1825 2950) $PN 193
J 2
(-1835 2960);
DISPLAY 0.680851 (-1835 2960);
PAINT MONO (-1835 2960);
FORCEPROP 0 LASTPIN (-1825 3000) $PN 195
J 2
(-1835 3010);
DISPLAY 0.680851 (-1835 3010);
PAINT MONO (-1835 3010);
FORCEPROP 0 LASTPIN (-1825 3050) $PN 197
J 2
(-1835 3060);
DISPLAY 0.680851 (-1835 3060);
PAINT MONO (-1835 3060);
FORCEPROP 0 LASTPIN (-1825 3100) $PN 199
J 2
(-1835 3110);
DISPLAY 0.680851 (-1835 3110);
PAINT MONO (-1835 3110);
FORCEPROP 0 LASTPIN (-1825 3150) $PN 202
J 2
(-1835 3160);
DISPLAY 0.680851 (-1835 3160);
PAINT MONO (-1835 3160);
FORCEPROP 0 LASTPIN (-1825 3200) $PN 204
J 2
(-1835 3210);
DISPLAY 0.680851 (-1835 3210);
PAINT MONO (-1835 3210);
FORCEPROP 0 LASTPIN (-1825 3250) $PN 206
J 2
(-1835 3260);
DISPLAY 0.680851 (-1835 3260);
PAINT MONO (-1835 3260);
FORCEPROP 0 LASTPIN (-1825 3300) $PN 208
J 2
(-1835 3310);
DISPLAY 0.680851 (-1835 3310);
PAINT MONO (-1835 3310);
FORCEPROP 0 LASTPIN (-1825 3350) $PN 210
J 2
(-1835 3360);
DISPLAY 0.680851 (-1835 3360);
PAINT MONO (-1835 3360);
FORCEPROP 0 LASTPIN (-1825 3400) $PN 212
J 2
(-1835 3410);
DISPLAY 0.680851 (-1835 3410);
PAINT MONO (-1835 3410);
FORCEPROP 0 LASTPIN (-1825 3450) $PN 214
J 2
(-1835 3460);
DISPLAY 0.680851 (-1835 3460);
PAINT MONO (-1835 3460);
FORCEPROP 0 LASTPIN (-1825 3500) $PN 216
J 2
(-1835 3510);
DISPLAY 0.680851 (-1835 3510);
PAINT MONO (-1835 3510);
FORCEPROP 0 LASTPIN (-1825 3550) $PN 219
J 2
(-1835 3560);
DISPLAY 0.680851 (-1835 3560);
PAINT MONO (-1835 3560);
FORCEPROP 0 LASTPIN (-1825 3600) $PN 222
J 2
(-1835 3610);
DISPLAY 0.680851 (-1835 3610);
PAINT MONO (-1835 3610);
FORCEPROP 0 LASTPIN (-1825 3650) $PN 224
J 2
(-1835 3660);
DISPLAY 0.680851 (-1835 3660);
PAINT MONO (-1835 3660);
FORCEPROP 0 LASTPIN (-1825 3700) $PN 226
J 2
(-1835 3710);
DISPLAY 0.680851 (-1835 3710);
PAINT MONO (-1835 3710);
FORCEPROP 0 LASTPIN (-1825 3750) $PN 228
J 2
(-1835 3760);
DISPLAY 0.680851 (-1835 3760);
PAINT MONO (-1835 3760);
FORCEPROP 0 LASTPIN (-1825 3800) $PN 230
J 2
(-1835 3810);
DISPLAY 0.680851 (-1835 3810);
PAINT MONO (-1835 3810);
FORCEPROP 0 LASTPIN (-1825 3850) $PN 233
J 2
(-1835 3860);
DISPLAY 0.680851 (-1835 3860);
PAINT MONO (-1835 3860);
FORCEPROP 0 LASTPIN (-1825 3900) $PN 235
J 2
(-1835 3910);
DISPLAY 0.680851 (-1835 3910);
PAINT MONO (-1835 3910);
FORCEPROP 0 LASTPIN (-1825 3950) $PN 237
J 2
(-1835 3960);
DISPLAY 0.680851 (-1835 3960);
PAINT MONO (-1835 3960);
FORCEPROP 0 LASTPIN (-1825 4000) $PN 240
J 2
(-1835 4010);
DISPLAY 0.680851 (-1835 4010);
PAINT MONO (-1835 4010);
FORCEPROP 0 LASTPIN (-1825 4050) $PN 242
J 2
(-1835 4060);
DISPLAY 0.680851 (-1835 4060);
PAINT MONO (-1835 4060);
FORCEPROP 0 LASTPIN (-1825 4100) $PN 244
J 2
(-1835 4110);
DISPLAY 0.680851 (-1835 4110);
PAINT MONO (-1835 4110);
FORCEPROP 0 LASTPIN (-1825 4150) $PN 246
J 2
(-1835 4160);
DISPLAY 0.680851 (-1835 4160);
PAINT MONO (-1835 4160);
FORCEPROP 0 LASTPIN (-1825 4200) $PN 248
J 2
(-1835 4210);
DISPLAY 0.680851 (-1835 4210);
PAINT MONO (-1835 4210);
FORCEPROP 0 LASTPIN (-1825 4250) $PN 251
J 2
(-1835 4260);
DISPLAY 0.680851 (-1835 4260);
PAINT MONO (-1835 4260);
FORCEPROP 0 LASTPIN (-1825 4300) $PN 253
J 2
(-1835 4310);
DISPLAY 0.680851 (-1835 4310);
PAINT MONO (-1835 4310);
FORCEPROP 0 LASTPIN (-1825 4350) $PN 255
J 2
(-1835 4360);
DISPLAY 0.680851 (-1835 4360);
PAINT MONO (-1835 4360);
FORCEPROP 0 LASTPIN (-1825 4400) $PN 257
J 2
(-1835 4410);
DISPLAY 0.680851 (-1835 4410);
PAINT MONO (-1835 4410);
FORCEPROP 0 LASTPIN (-1825 4450) $PN 259
J 2
(-1835 4460);
DISPLAY 0.680851 (-1835 4460);
PAINT MONO (-1835 4460);
FORCEPROP 0 LASTPIN (-1825 4500) $PN 262
J 2
(-1835 4510);
DISPLAY 0.680851 (-1835 4510);
PAINT MONO (-1835 4510);
FORCEPROP 0 LASTPIN (-1825 4550) $PN 264
J 2
(-1835 4560);
DISPLAY 0.680851 (-1835 4560);
PAINT MONO (-1835 4560);
FORCEPROP 0 LASTPIN (-1825 4600) $PN 266
J 2
(-1835 4610);
DISPLAY 0.680851 (-1835 4610);
PAINT MONO (-1835 4610);
FORCEPROP 0 LASTPIN (-1825 4650) $PN 268
J 2
(-1835 4660);
DISPLAY 0.680851 (-1835 4660);
PAINT MONO (-1835 4660);
FORCEPROP 0 LASTPIN (-1825 4700) $PN 270
J 2
(-1835 4710);
DISPLAY 0.680851 (-1835 4710);
PAINT MONO (-1835 4710);
FORCEPROP 0 LASTPIN (-1825 4750) $PN 273
J 2
(-1835 4760);
DISPLAY 0.680851 (-1835 4760);
PAINT MONO (-1835 4760);
FORCEPROP 0 LASTPIN (-1825 4800) $PN 275
J 2
(-1835 4810);
DISPLAY 0.680851 (-1835 4810);
PAINT MONO (-1835 4810);
FORCEPROP 0 LASTPIN (-1825 4850) $PN 277
J 2
(-1835 4860);
DISPLAY 0.680851 (-1835 4860);
PAINT MONO (-1835 4860);
FORCEPROP 0 LASTPIN (-1825 4900) $PN 279
J 2
(-1835 4910);
DISPLAY 0.680851 (-1835 4910);
PAINT MONO (-1835 4910);
FORCEPROP 0 LASTPIN (-1825 4950) $PN 281
J 2
(-1835 4960);
DISPLAY 0.680851 (-1835 4960);
PAINT MONO (-1835 4960);
FORCEPROP 0 LASTPIN (-1825 5000) $PN 284
J 2
(-1835 5010);
DISPLAY 0.680851 (-1835 5010);
PAINT MONO (-1835 5010);
FORCEPROP 0 LASTPIN (-1825 5050) $PN 286
J 2
(-1835 5060);
DISPLAY 0.680851 (-1835 5060);
PAINT MONO (-1835 5060);
FORCEPROP 0 LASTPIN (-1825 5100) $PN 288
J 2
(-1835 5110);
DISPLAY 0.680851 (-1835 5110);
PAINT MONO (-1835 5110);
FORCEPROP 2 LAST PART_TYPE SMLF
J 0
(-1675 5675);
DISPLAY 1.021277 (-1675 5675);
FORCEPROP 1 LAST MATERIAL IO
J 0
(-1675 5425);
DISPLAY 0.468085 (-1675 5425);
PAINT SKYBLUE (-1675 5425);
FORCEPROP 2 LAST VALUE SCONN288_DDR506112002KQ
J 0
(-1675 5625);
DISPLAY 0.489362 (-1675 5625);
PAINT SKYBLUE (-1675 5625);
FORCEPROP 1 LAST CDS_LMAN_SYM_OUTLINE -450,1800,450,-1750
J 0
(-1225 3600);
DISPLAY 0.468085 (-1225 3600);
PAINT GREEN (-1225 3600);
DISPLAY INVISIBLE (-1225 3600);
FORCEPROP 1 LAST NEEDS_NO_SIZE TRUE
J 0
(-1225 3600);
DISPLAY 0.723404 (-1225 3600);
PAINT GREEN (-1225 3600);
DISPLAY INVISIBLE (-1225 3600);
FORCEPROP 2 LAST CDS_LIB pure_quanta
J 0
(-1225 3600);
DISPLAY INVISIBLE (-1225 3600);
FORCEPROP 1 LAST PATH I176
J 0
(-1225 3600);
DISPLAY 0.723404 (-1225 3600);
PAINT GREEN (-1225 3600);
DISPLAY INVISIBLE (-1225 3600);
FORCEPROP 1 LAST PART_NUMBER DFHST8FS479
J 0
(-1675 5500);
DISPLAY 0.468085 (-1675 5500);
PAINT SKYBLUE (-1675 5500);
DISPLAY INVISIBLE (-1675 5500);
FORCEADD OFFPAGE..1
(-8275 4400);
FORCEPROP 2 LAST $XR0 45 
J 0
(-8526 4400);
DISPLAY 0.638298 (-8526 4400);
PAINT MONO (-8526 4400);
FORCEPROP 2 LAST CDS_LIB mstr_standard
J 0
(-8275 4400);
DISPLAY 0.723404 (-8275 4400);
PAINT MONO (-8275 4400);
DISPLAY INVISIBLE (-8275 4400);
FORCEPROP 1 LAST OFFPAGE TRUE
J 0
(-7950 4275);
DISPLAY 0.872340 (-7950 4275);
PAINT GREEN (-7950 4275);
DISPLAY INVISIBLE (-7950 4275);
FORCEPROP 1 LAST COMMENT_BODY TRUE
J 0
(-8150 4300);
DISPLAY 0.872340 (-8150 4300);
PAINT GREEN (-8150 4300);
DISPLAY INVISIBLE (-8150 4300);
FORCEPROP 2 LAST PATH I18
J 0
(-8525 4450);
DISPLAY 1.021277 (-8525 4450);
DISPLAY INVISIBLE (-8525 4450);
FORCEADD Q_CAP..1
R 2
(-8550 3175);
FORCEPROP 1 LAST LOCATION C168
J 2
(-8600 3275);
DISPLAY 0.489362 (-8600 3275);
PAINT SKYBLUE (-8600 3275);
FORCEPROP 0 LAST $SEC 1
J 0
(-8600 3325);
DISPLAY 0.680851 (-8600 3325);
PAINT MONO (-8600 3325);
DISPLAY INVISIBLE (-8600 3325);
FORCEPROP 0 LAST CDS_SEC 1
J 0
(-8600 3325);
DISPLAY 1.021277 (-8600 3325);
DISPLAY INVISIBLE (-8600 3325);
FORCEPROP 1 LASTPIN (-8550 3275) $PN 1
J 2
(-8560 3255);
DISPLAY 0.489362 (-8560 3255);
PAINT MONO (-8560 3255);
FORCEPROP 1 LASTPIN (-8550 3075) $PN 2
J 2
(-8560 3055);
DISPLAY 0.489362 (-8560 3055);
PAINT MONO (-8560 3055);
FORCEPROP 1 LAST TOLERANCE 10%
J 2
(-8600 3125);
DISPLAY 0.489362 (-8600 3125);
PAINT SKYBLUE (-8600 3125);
FORCEPROP 1 LAST MATERIAL X7R
J 2
(-8600 3075);
DISPLAY 0.489362 (-8600 3075);
PAINT SKYBLUE (-8600 3075);
FORCEPROP 1 LAST VALUE 0.1UF
J 2
(-8600 3225);
DISPLAY 0.489362 (-8600 3225);
PAINT SKYBLUE (-8600 3225);
FORCEPROP 1 LAST VOLTAGE 25V
J 2
(-8600 3175);
DISPLAY 0.489362 (-8600 3175);
PAINT SKYBLUE (-8600 3175);
FORCEPROP 1 LAST PACK_TYPE 0402
J 2
(-8600 2975);
DISPLAY 0.489362 (-8600 2975);
PAINT SKYBLUE (-8600 2975);
FORCEPROP 2 LAST CDS_LIB pure_quanta
J 0
(-8550 3175);
DISPLAY INVISIBLE (-8550 3175);
FORCEPROP 0 LAST BOM_COST MEM
J 2
(-8605 3320);
DISPLAY 0.595745 (-8605 3320);
PAINT MONO (-8605 3320);
DISPLAY INVISIBLE (-8605 3320);
FORCEPROP 2 LAST ROOM 
J 2
(-8605 3320);
DISPLAY 0.595745 (-8605 3320);
PAINT RED (-8605 3320);
DISPLAY INVISIBLE (-8605 3320);
FORCEPROP 1 LAST PATH I185
J 2
(-8600 3325);
DISPLAY 0.978723 (-8600 3325);
PAINT WHITE (-8600 3325);
DISPLAY INVISIBLE (-8600 3325);
FORCEPROP 1 LAST PART_NUMBER CH4104K1B00
J 2
(-8600 3025);
DISPLAY 0.489362 (-8600 3025);
PAINT SKYBLUE (-8600 3025);
DISPLAY INVISIBLE (-8600 3025);
FORCEADD GND..1
(-8550 2950);
FORCEPROP 3 LASTPIN (-8550 3000) SIG_NAME GND\g
J 0
(-8540 3010);
DISPLAY 0.659574 (-8540 3010);
PAINT MONO (-8540 3010);
DISPLAY INVISIBLE (-8540 3010);
FORCEPROP 2 LAST BOM_COST MEM
J 0
(-8525 3075);
DISPLAY 0.659574 (-8525 3075);
DISPLAY INVISIBLE (-8525 3075);
FORCEPROP 1 LAST SIZE 1B
J 0
(-8475 2900);
DISPLAY 0.723404 (-8475 2900);
PAINT GREEN (-8475 2900);
DISPLAY INVISIBLE (-8475 2900);
FORCEPROP 2 LAST CDS_LIB mstr_symbols
J 0
(-8550 2950);
DISPLAY 0.808511 (-8550 2950);
DISPLAY INVISIBLE (-8550 2950);
FORCEPROP 1 LAST VOLTAGE 0
J 0
(-8570 3045);
DISPLAY 0.829787 (-8570 3045);
PAINT SKYBLUE (-8570 3045);
DISPLAY INVISIBLE (-8570 3045);
FORCEPROP 2 LAST ROOM MEM_EFGH_DECOUPLING_CAPS
J 0
(-8525 3025);
DISPLAY 0.659574 (-8525 3025);
PAINT RED (-8525 3025);
DISPLAY INVISIBLE (-8525 3025);
FORCEPROP 1 LAST BODY_TYPE PLUMBING
J 0
(-8595 2907);
DISPLAY 0.276596 (-8595 2907);
PAINT GREEN (-8595 2907);
DISPLAY INVISIBLE (-8595 2907);
FORCEPROP 1 LAST HDL_POWER GND
J 0
(-8550 3100);
DISPLAY 0.723404 (-8550 3100);
PAINT GREEN (-8550 3100);
DISPLAY INVISIBLE (-8550 3100);
FORCEPROP 1 LAST PATH I186
J 0
(-8475 2950);
DISPLAY 0.872340 (-8475 2950);
PAINT AQUA (-8475 2950);
DISPLAY INVISIBLE (-8475 2950);
FORCEADD OFFPAGE..6
(-9025 2100);
FORCEPROP 2 LAST $XR4 109 
J 0
(-9305 2172);
DISPLAY 0.638298 (-9305 2172);
PAINT MONO (-9305 2172);
FORCEPROP 2 LAST $XR3 108 
J 0
(-9305 2028);
DISPLAY 0.638298 (-9305 2028);
PAINT MONO (-9305 2028);
FORCEPROP 2 LAST $XR2 107 
J 0
(-9305 2136);
DISPLAY 0.638298 (-9305 2136);
PAINT MONO (-9305 2136);
FORCEPROP 2 LAST $XR1 105 
J 0
(-9305 2064);
DISPLAY 0.638298 (-9305 2064);
PAINT MONO (-9305 2064);
FORCEPROP 2 LAST $XR0 104 
J 0
(-9305 2100);
DISPLAY 0.638298 (-9305 2100);
PAINT MONO (-9305 2100);
FORCEPROP 2 LAST CDS_LIB mstr_standard
J 0
(-9025 2100);
DISPLAY INVISIBLE (-9025 2100);
FORCEPROP 1 LAST OFFPAGE TRUE
J 0
(-8700 1975);
DISPLAY 0.872340 (-8700 1975);
PAINT GREEN (-8700 1975);
DISPLAY INVISIBLE (-8700 1975);
FORCEPROP 1 LAST COMMENT_BODY TRUE
J 0
(-8925 2025);
DISPLAY 0.872340 (-8925 2025);
PAINT GREEN (-8925 2025);
DISPLAY INVISIBLE (-8925 2025);
FORCEPROP 2 LAST PATH I187
J 0
(-8975 2175);
DISPLAY 1.021277 (-8975 2175);
DISPLAY INVISIBLE (-8975 2175);
FORCEADD Q_RES..1
R 2
(-8475 2100);
FORCEPROP 1 LAST LOCATION R311
J 2
(-8425 2150);
DISPLAY 0.489362 (-8425 2150);
PAINT SKYBLUE (-8425 2150);
FORCEPROP 0 LAST $SEC 1
J 0
(-8425 2200);
DISPLAY 0.680851 (-8425 2200);
PAINT MONO (-8425 2200);
DISPLAY INVISIBLE (-8425 2200);
FORCEPROP 0 LAST CDS_SEC 1
J 0
(-8425 2200);
DISPLAY 1.021277 (-8425 2200);
DISPLAY INVISIBLE (-8425 2200);
FORCEPROP 1 LASTPIN (-8375 2100) $PN 1
J 2
(-8387 2112);
DISPLAY 0.489362 (-8387 2112);
PAINT MONO (-8387 2112);
FORCEPROP 1 LASTPIN (-8575 2100) $PN 2
J 2
(-8537 2112);
DISPLAY 0.489362 (-8537 2112);
PAINT MONO (-8537 2112);
FORCEPROP 1 LAST VALUE 1K
J 0
(-8475 2050);
DISPLAY 0.489362 (-8475 2050);
PAINT SKYBLUE (-8475 2050);
FORCEPROP 1 LAST TOLERANCE 1%
J 2
(-8350 2075);
DISPLAY 0.489362 (-8350 2075);
PAINT SKYBLUE (-8350 2075);
DISPLAY INVISIBLE (-8350 2075);
FORCEPROP 2 LAST CDS_LIB pure_quanta
J 0
(-8475 2100);
DISPLAY INVISIBLE (-8475 2100);
FORCEPROP 2 LAST BOM_COST MEM
J 0
(-8500 2250);
DISPLAY 0.744681 (-8500 2250);
PAINT WHITE (-8500 2250);
DISPLAY INVISIBLE (-8500 2250);
FORCEPROP 1 LAST WATTAGE 1/16W
J 0
(-8400 2025);
DISPLAY 0.489362 (-8400 2025);
PAINT SKYBLUE (-8400 2025);
DISPLAY INVISIBLE (-8400 2025);
FORCEPROP 1 LAST MATERIAL CHIP
J 0
(-8650 2075);
DISPLAY 0.489362 (-8650 2075);
PAINT SKYBLUE (-8650 2075);
DISPLAY INVISIBLE (-8650 2075);
FORCEPROP 1 LAST PACK_TYPE 0402LF
J 0
(-8650 2025);
DISPLAY 0.489362 (-8650 2025);
PAINT SKYBLUE (-8650 2025);
DISPLAY INVISIBLE (-8650 2025);
FORCEPROP 2 LAST ROOM 
J 0
(-8500 2200);
DISPLAY 0.744681 (-8500 2200);
PAINT RED (-8500 2200);
DISPLAY INVISIBLE (-8500 2200);
FORCEPROP 1 LAST PATH I188
J 2
(-8425 2250);
DISPLAY 0.978723 (-8425 2250);
PAINT WHITE (-8425 2250);
DISPLAY INVISIBLE (-8425 2250);
FORCEPROP 1 LAST PART_NUMBER CS21002FB06
J 0
(-8575 2150);
DISPLAY 0.489362 (-8575 2150);
PAINT SKYBLUE (-8575 2150);
DISPLAY INVISIBLE (-8575 2150);
FORCEADD VCC_CORE..1
(-8350 2425);
FORCEPROP 3 LASTPIN (-8350 2375) SIG_NAME P3V3\g
J 0
(-8340 2385);
DISPLAY 0.659574 (-8340 2385);
PAINT MONO (-8340 2385);
DISPLAY INVISIBLE (-8340 2385);
FORCEPROP 1 LAST HDL_POWER P3V3
J 1
(-8350 2475);
DISPLAY 0.489362 (-8350 2475);
PAINT GREEN (-8350 2475);
FORCEPROP 2 LAST CDS_LIB mstr_symbols
J 0
(-8350 2425);
DISPLAY INVISIBLE (-8350 2425);
FORCEPROP 0 LAST VOLTAGE 3.3
J 0
(-8625 2575);
DISPLAY 1.021277 (-8625 2575);
PAINT SKYBLUE (-8625 2575);
DISPLAY INVISIBLE (-8625 2575);
FORCEPROP 2 LAST ROOM PVCCINFAON_CPU0_CTRL
J 0
(-8350 2525);
DISPLAY 0.808511 (-8350 2525);
PAINT RED (-8350 2525);
DISPLAY INVISIBLE (-8350 2525);
FORCEPROP 1 LAST PATH I189
J 0
(-8300 2450);
DISPLAY 0.872340 (-8300 2450);
PAINT AQUA (-8300 2450);
DISPLAY INVISIBLE (-8300 2450);
FORCEADD OFFPAGE..1
(-8275 4550);
FORCEPROP 2 LAST $XR0 45 
J 0
(-8526 4550);
DISPLAY 0.638298 (-8526 4550);
PAINT MONO (-8526 4550);
FORCEPROP 2 LAST CDS_LIB mstr_standard
J 0
(-8275 4550);
DISPLAY 0.723404 (-8275 4550);
PAINT MONO (-8275 4550);
DISPLAY INVISIBLE (-8275 4550);
FORCEPROP 1 LAST OFFPAGE TRUE
J 0
(-7950 4425);
DISPLAY 0.872340 (-7950 4425);
PAINT GREEN (-7950 4425);
DISPLAY INVISIBLE (-7950 4425);
FORCEPROP 1 LAST COMMENT_BODY TRUE
J 0
(-8150 4450);
DISPLAY 0.872340 (-8150 4450);
PAINT GREEN (-8150 4450);
DISPLAY INVISIBLE (-8150 4450);
FORCEPROP 2 LAST PATH I19
J 0
(-8525 4600);
DISPLAY 1.021277 (-8525 4600);
DISPLAY INVISIBLE (-8525 4600);
FORCEADD Q_RES..2
(-8350 2250);
FORCEPROP 1 LAST LOCATION R112
J 0
(-8305 2375);
DISPLAY 0.489362 (-8305 2375);
PAINT SKYBLUE (-8305 2375);
FORCEPROP 0 LAST $SEC 1
J 0
(-8300 2425);
DISPLAY 0.680851 (-8300 2425);
PAINT MONO (-8300 2425);
DISPLAY INVISIBLE (-8300 2425);
FORCEPROP 0 LAST CDS_SEC 1
J 0
(-8300 2425);
DISPLAY 1.021277 (-8300 2425);
DISPLAY INVISIBLE (-8300 2425);
FORCEPROP 1 LASTPIN (-8350 2350) $PN 1
J 0
(-8345 2312);
DISPLAY 0.489362 (-8345 2312);
PAINT MONO (-8345 2312);
FORCEPROP 1 LASTPIN (-8350 2150) $PN 2
J 0
(-8345 2160);
DISPLAY 0.489362 (-8345 2160);
PAINT MONO (-8345 2160);
FORCEPROP 1 LAST MATERIAL EMPTY
J 0
(-8300 2250);
DISPLAY 0.489362 (-8300 2250);
PAINT RED (-8300 2250);
FORCEPROP 1 LAST WATTAGE 1/16W
J 0
(-8300 2275);
DISPLAY 0.489362 (-8300 2275);
PAINT SKYBLUE (-8300 2275);
FORCEPROP 1 LAST TOLERANCE 1%
J 0
(-8300 2300);
DISPLAY 0.489362 (-8300 2300);
PAINT SKYBLUE (-8300 2300);
FORCEPROP 1 LAST VALUE 1K
J 0
(-8305 2325);
DISPLAY 0.489362 (-8305 2325);
PAINT SKYBLUE (-8305 2325);
FORCEPROP 1 LAST PACK_TYPE 0402LF
J 0
(-8300 2200);
DISPLAY 0.489362 (-8300 2200);
PAINT SKYBLUE (-8300 2200);
FORCEPROP 2 LAST CDS_LIB pure_quanta
J 0
(-8350 2250);
DISPLAY INVISIBLE (-8350 2250);
FORCEPROP 2 LAST BOM_COST MEM
J 0
(-8300 2425);
DISPLAY 0.808511 (-8300 2425);
DISPLAY INVISIBLE (-8300 2425);
FORCEPROP 2 LAST ROOM 
J 0
(-8300 2475);
DISPLAY 0.808511 (-8300 2475);
PAINT RED (-8300 2475);
DISPLAY INVISIBLE (-8300 2475);
FORCEPROP 1 LAST PATH I190
J 0
(-8300 2425);
DISPLAY 0.978723 (-8300 2425);
PAINT WHITE (-8300 2425);
DISPLAY INVISIBLE (-8300 2425);
FORCEPROP 1 LAST PART_NUMBER CS21002FB06
J 0
(-8300 2225);
DISPLAY 0.489362 (-8300 2225);
PAINT SKYBLUE (-8300 2225);
DISPLAY INVISIBLE (-8300 2225);
FORCEADD TAP..1
(-3250 3100);
FORCEPROP 3 LASTPIN (-3300 3100) SIG_NAME M_I_CPU1_SB_DQS_DN<7>
J 0
(-3290 3110);
DISPLAY 0.659574 (-3290 3110);
PAINT MONO (-3290 3110);
DISPLAY INVISIBLE (-3290 3110);
FORCEPROP 1 LASTPIN (-3300 3100) BN 7
J 0
(-3312 3108);
DISPLAY 0.489362 (-3312 3108);
PAINT GREEN (-3312 3108);
FORCEPROP 2 LAST CDS_LIB mstr_standard
J 0
(-3250 3100);
DISPLAY 0.723404 (-3250 3100);
PAINT MONO (-3250 3100);
DISPLAY INVISIBLE (-3250 3100);
FORCEPROP 1 LAST BODY_TYPE PLUMBING
J 0
(-3250 3150);
DISPLAY 0.872340 (-3250 3150);
PAINT GREEN (-3250 3150);
DISPLAY INVISIBLE (-3250 3150);
FORCEPROP 1 LAST HDL_TAP TRUE
J 0
(-2925 2975);
DISPLAY 0.872340 (-2925 2975);
DISPLAY INVISIBLE (-2925 2975);
FORCEPROP 1 LAST PATH I191
J 0
(-3252 3100);
DISPLAY 0.872340 (-3252 3100);
PAINT GREEN (-3252 3100);
DISPLAY INVISIBLE (-3252 3100);
FORCEADD TAP..1
(-3250 3300);
FORCEPROP 3 LASTPIN (-3300 3300) SIG_NAME M_I_CPU1_SB_DQS_DN<9>
J 0
(-3290 3310);
DISPLAY 0.659574 (-3290 3310);
PAINT MONO (-3290 3310);
DISPLAY INVISIBLE (-3290 3310);
FORCEPROP 1 LASTPIN (-3300 3300) BN 9
J 0
(-3312 3308);
DISPLAY 0.489362 (-3312 3308);
PAINT GREEN (-3312 3308);
FORCEPROP 2 LAST CDS_LIB mstr_standard
J 0
(-3250 3300);
DISPLAY 0.723404 (-3250 3300);
PAINT MONO (-3250 3300);
DISPLAY INVISIBLE (-3250 3300);
FORCEPROP 1 LAST BODY_TYPE PLUMBING
J 0
(-3250 3350);
DISPLAY 0.872340 (-3250 3350);
PAINT GREEN (-3250 3350);
DISPLAY INVISIBLE (-3250 3350);
FORCEPROP 1 LAST HDL_TAP TRUE
J 0
(-2925 3175);
DISPLAY 0.872340 (-2925 3175);
DISPLAY INVISIBLE (-2925 3175);
FORCEPROP 1 LAST PATH I192
J 0
(-3252 3300);
DISPLAY 0.872340 (-3252 3300);
PAINT GREEN (-3252 3300);
DISPLAY INVISIBLE (-3252 3300);
FORCEADD TAP..1
(-3250 3450);
FORCEPROP 3 LASTPIN (-3300 3450) SIG_NAME M_I_CPU1_SA_DQS_DN<0>
J 0
(-3290 3460);
DISPLAY 0.659574 (-3290 3460);
PAINT MONO (-3290 3460);
DISPLAY INVISIBLE (-3290 3460);
FORCEPROP 1 LASTPIN (-3300 3450) BN 0
J 0
(-3312 3458);
DISPLAY 0.489362 (-3312 3458);
PAINT GREEN (-3312 3458);
FORCEPROP 2 LAST CDS_LIB mstr_standard
J 0
(-3250 3450);
DISPLAY 0.723404 (-3250 3450);
PAINT MONO (-3250 3450);
DISPLAY INVISIBLE (-3250 3450);
FORCEPROP 1 LAST BODY_TYPE PLUMBING
J 0
(-3250 3500);
DISPLAY 0.872340 (-3250 3500);
PAINT GREEN (-3250 3500);
DISPLAY INVISIBLE (-3250 3500);
FORCEPROP 1 LAST HDL_TAP TRUE
J 0
(-2925 3325);
DISPLAY 0.872340 (-2925 3325);
DISPLAY INVISIBLE (-2925 3325);
FORCEPROP 1 LAST PATH I193
J 0
(-3252 3450);
DISPLAY 0.872340 (-3252 3450);
PAINT GREEN (-3252 3450);
DISPLAY INVISIBLE (-3252 3450);
FORCEADD TAP..1
(-3250 3550);
FORCEPROP 3 LASTPIN (-3300 3550) SIG_NAME M_I_CPU1_SA_DQS_DN<1>
J 0
(-3290 3560);
DISPLAY 0.659574 (-3290 3560);
PAINT MONO (-3290 3560);
DISPLAY INVISIBLE (-3290 3560);
FORCEPROP 1 LASTPIN (-3300 3550) BN 1
J 0
(-3312 3558);
DISPLAY 0.489362 (-3312 3558);
PAINT GREEN (-3312 3558);
FORCEPROP 2 LAST CDS_LIB mstr_standard
J 0
(-3250 3550);
DISPLAY 0.723404 (-3250 3550);
PAINT MONO (-3250 3550);
DISPLAY INVISIBLE (-3250 3550);
FORCEPROP 1 LAST BODY_TYPE PLUMBING
J 0
(-3250 3600);
DISPLAY 0.872340 (-3250 3600);
PAINT GREEN (-3250 3600);
DISPLAY INVISIBLE (-3250 3600);
FORCEPROP 1 LAST HDL_TAP TRUE
J 0
(-2925 3425);
DISPLAY 0.872340 (-2925 3425);
DISPLAY INVISIBLE (-2925 3425);
FORCEPROP 1 LAST PATH I194
J 0
(-3252 3550);
DISPLAY 0.872340 (-3252 3550);
PAINT GREEN (-3252 3550);
DISPLAY INVISIBLE (-3252 3550);
FORCEADD TAP..1
(-3450 3800);
FORCEPROP 3 LASTPIN (-3500 3800) SIG_NAME M_I_CPU1_SA_DQS_DP<3>
J 0
(-3490 3810);
DISPLAY 0.659574 (-3490 3810);
PAINT MONO (-3490 3810);
DISPLAY INVISIBLE (-3490 3810);
FORCEPROP 1 LASTPIN (-3500 3800) BN 3
J 0
(-3512 3808);
DISPLAY 0.489362 (-3512 3808);
PAINT GREEN (-3512 3808);
FORCEPROP 2 LAST CDS_LIB mstr_standard
J 0
(-3450 3800);
DISPLAY 0.723404 (-3450 3800);
PAINT MONO (-3450 3800);
DISPLAY INVISIBLE (-3450 3800);
FORCEPROP 1 LAST BODY_TYPE PLUMBING
J 0
(-3450 3850);
DISPLAY 0.872340 (-3450 3850);
PAINT GREEN (-3450 3850);
DISPLAY INVISIBLE (-3450 3850);
FORCEPROP 1 LAST HDL_TAP TRUE
J 0
(-3125 3675);
DISPLAY 0.872340 (-3125 3675);
DISPLAY INVISIBLE (-3125 3675);
FORCEPROP 1 LAST PATH I195
J 0
(-3452 3800);
DISPLAY 0.872340 (-3452 3800);
PAINT GREEN (-3452 3800);
DISPLAY INVISIBLE (-3452 3800);
FORCEADD OFFPAGE..2
(-2450 4450);
FORCEPROP 2 LAST $XR0 45 
J 0
(-2261 4450);
DISPLAY 0.638298 (-2261 4450);
PAINT MONO (-2261 4450);
FORCEPROP 2 LAST CDS_LIB mstr_standard
J 0
(-2450 4450);
DISPLAY 0.723404 (-2450 4450);
PAINT MONO (-2450 4450);
DISPLAY INVISIBLE (-2450 4450);
FORCEPROP 1 LAST OFFPAGE TRUE
J 0
(-2125 4325);
DISPLAY 0.723404 (-2125 4325);
PAINT GREEN (-2125 4325);
DISPLAY INVISIBLE (-2125 4325);
FORCEPROP 1 LAST COMMENT_BODY TRUE
J 0
(-2495 4355);
DISPLAY 0.872340 (-2495 4355);
PAINT GREEN (-2495 4355);
DISPLAY INVISIBLE (-2495 4355);
FORCEPROP 2 LAST PATH I197
J 0
(-2250 4500);
DISPLAY 0.680851 (-2250 4500);
DISPLAY INVISIBLE (-2250 4500);
FORCEADD OFFPAGE..2
(-2450 4400);
FORCEPROP 2 LAST $XR0 45 
J 0
(-2261 4400);
DISPLAY 0.638298 (-2261 4400);
PAINT MONO (-2261 4400);
FORCEPROP 2 LAST CDS_LIB mstr_standard
J 0
(-2450 4400);
DISPLAY 0.723404 (-2450 4400);
PAINT MONO (-2450 4400);
DISPLAY INVISIBLE (-2450 4400);
FORCEPROP 1 LAST OFFPAGE TRUE
J 0
(-2125 4275);
DISPLAY 0.723404 (-2125 4275);
PAINT GREEN (-2125 4275);
DISPLAY INVISIBLE (-2125 4275);
FORCEPROP 1 LAST COMMENT_BODY TRUE
J 0
(-2495 4305);
DISPLAY 0.872340 (-2495 4305);
PAINT GREEN (-2495 4305);
DISPLAY INVISIBLE (-2495 4305);
FORCEPROP 2 LAST PATH I198
J 0
(-2250 4450);
DISPLAY 0.680851 (-2250 4450);
DISPLAY INVISIBLE (-2250 4450);
FORCEADD OFFPAGE..2
(-2450 3400);
FORCEPROP 2 LAST $XR0 45 
J 0
(-2261 3400);
DISPLAY 0.638298 (-2261 3400);
PAINT MONO (-2261 3400);
FORCEPROP 2 LAST CDS_LIB mstr_standard
J 0
(-2450 3400);
DISPLAY 0.723404 (-2450 3400);
PAINT MONO (-2450 3400);
DISPLAY INVISIBLE (-2450 3400);
FORCEPROP 1 LAST OFFPAGE TRUE
J 0
(-2125 3275);
DISPLAY 0.723404 (-2125 3275);
PAINT GREEN (-2125 3275);
DISPLAY INVISIBLE (-2125 3275);
FORCEPROP 1 LAST COMMENT_BODY TRUE
J 0
(-2495 3305);
DISPLAY 0.872340 (-2495 3305);
PAINT GREEN (-2495 3305);
DISPLAY INVISIBLE (-2495 3305);
FORCEPROP 2 LAST PATH I199
J 0
(-2250 3450);
DISPLAY 0.680851 (-2250 3450);
DISPLAY INVISIBLE (-2250 3450);
FORCEADD OFFPAGE..5
(-8275 1950);
FORCEPROP 2 LAST $XR0 45 
J 0
(-8529 1950);
DISPLAY 0.638298 (-8529 1950);
PAINT MONO (-8529 1950);
FORCEPROP 2 LAST CDS_LIB mstr_standard
J 0
(-8275 1950);
DISPLAY 0.808511 (-8275 1950);
DISPLAY INVISIBLE (-8275 1950);
FORCEPROP 1 LAST OFFPAGE TRUE
J 0
(-7950 1825);
DISPLAY 0.872340 (-7950 1825);
PAINT GREEN (-7950 1825);
DISPLAY INVISIBLE (-7950 1825);
FORCEPROP 1 LAST COMMENT_BODY TRUE
J 0
(-8175 1875);
DISPLAY 0.872340 (-8175 1875);
PAINT GREEN (-8175 1875);
DISPLAY INVISIBLE (-8175 1875);
FORCEPROP 2 LAST PATH I2
J 0
(-8475 2000);
DISPLAY 1.021277 (-8475 2000);
DISPLAY INVISIBLE (-8475 2000);
FORCEADD OFFPAGE..1
(-8275 5400);
FORCEPROP 2 LAST $XR0 45 
J 0
(-8526 5400);
DISPLAY 0.638298 (-8526 5400);
PAINT MONO (-8526 5400);
FORCEPROP 2 LAST CDS_LIB mstr_standard
J 0
(-8275 5400);
DISPLAY 0.723404 (-8275 5400);
PAINT MONO (-8275 5400);
DISPLAY INVISIBLE (-8275 5400);
FORCEPROP 1 LAST OFFPAGE TRUE
J 0
(-7950 5275);
DISPLAY 0.872340 (-7950 5275);
PAINT GREEN (-7950 5275);
DISPLAY INVISIBLE (-7950 5275);
FORCEPROP 1 LAST COMMENT_BODY TRUE
J 0
(-8150 5300);
DISPLAY 0.872340 (-8150 5300);
PAINT GREEN (-8150 5300);
DISPLAY INVISIBLE (-8150 5300);
FORCEPROP 2 LAST PATH I20
J 0
(-8525 5450);
DISPLAY 1.021277 (-8525 5450);
DISPLAY INVISIBLE (-8525 5450);
FORCEADD OFFPAGE..2
(-2450 3350);
FORCEPROP 2 LAST $XR0 45 
J 0
(-2261 3350);
DISPLAY 0.638298 (-2261 3350);
PAINT MONO (-2261 3350);
FORCEPROP 2 LAST CDS_LIB mstr_standard
J 0
(-2450 3350);
DISPLAY 0.723404 (-2450 3350);
PAINT MONO (-2450 3350);
DISPLAY INVISIBLE (-2450 3350);
FORCEPROP 1 LAST OFFPAGE TRUE
J 0
(-2125 3225);
DISPLAY 0.723404 (-2125 3225);
PAINT GREEN (-2125 3225);
DISPLAY INVISIBLE (-2125 3225);
FORCEPROP 1 LAST COMMENT_BODY TRUE
J 0
(-2495 3255);
DISPLAY 0.872340 (-2495 3255);
PAINT GREEN (-2495 3255);
DISPLAY INVISIBLE (-2495 3255);
FORCEPROP 2 LAST PATH I200
J 0
(-2250 3400);
DISPLAY 0.680851 (-2250 3400);
DISPLAY INVISIBLE (-2250 3400);
FORCEADD TAP..1
(-3250 4350);
FORCEPROP 3 LASTPIN (-3300 4350) SIG_NAME M_I_CPU1_SA_DQS_DN<9>
J 0
(-3290 4360);
DISPLAY 0.659574 (-3290 4360);
PAINT MONO (-3290 4360);
DISPLAY INVISIBLE (-3290 4360);
FORCEPROP 1 LASTPIN (-3300 4350) BN 9
J 0
(-3312 4358);
DISPLAY 0.489362 (-3312 4358);
PAINT GREEN (-3312 4358);
FORCEPROP 2 LAST CDS_LIB mstr_standard
J 0
(-3250 4350);
DISPLAY 0.723404 (-3250 4350);
PAINT MONO (-3250 4350);
DISPLAY INVISIBLE (-3250 4350);
FORCEPROP 1 LAST BODY_TYPE PLUMBING
J 0
(-3250 4400);
DISPLAY 0.872340 (-3250 4400);
PAINT GREEN (-3250 4400);
DISPLAY INVISIBLE (-3250 4400);
FORCEPROP 1 LAST HDL_TAP TRUE
J 0
(-2925 4225);
DISPLAY 0.872340 (-2925 4225);
DISPLAY INVISIBLE (-2925 4225);
FORCEPROP 1 LAST PATH I201
J 0
(-3252 4350);
DISPLAY 0.872340 (-3252 4350);
PAINT GREEN (-3252 4350);
DISPLAY INVISIBLE (-3252 4350);
FORCEADD TAP..1
(-3450 4400);
FORCEPROP 3 LASTPIN (-3500 4400) SIG_NAME M_I_CPU1_SA_DQS_DP<9>
J 0
(-3490 4410);
DISPLAY 0.659574 (-3490 4410);
PAINT MONO (-3490 4410);
DISPLAY INVISIBLE (-3490 4410);
FORCEPROP 1 LASTPIN (-3500 4400) BN 9
J 0
(-3512 4408);
DISPLAY 0.489362 (-3512 4408);
PAINT GREEN (-3512 4408);
FORCEPROP 2 LAST CDS_LIB mstr_standard
J 0
(-3450 4400);
DISPLAY 0.723404 (-3450 4400);
PAINT MONO (-3450 4400);
DISPLAY INVISIBLE (-3450 4400);
FORCEPROP 1 LAST BODY_TYPE PLUMBING
J 0
(-3450 4450);
DISPLAY 0.872340 (-3450 4450);
PAINT GREEN (-3450 4450);
DISPLAY INVISIBLE (-3450 4450);
FORCEPROP 1 LAST HDL_TAP TRUE
J 0
(-3125 4275);
DISPLAY 0.872340 (-3125 4275);
DISPLAY INVISIBLE (-3125 4275);
FORCEPROP 1 LAST PATH I202
J 0
(-3452 4400);
DISPLAY 0.872340 (-3452 4400);
PAINT GREEN (-3452 4400);
DISPLAY INVISIBLE (-3452 4400);
FORCEADD TAP..1
(-3450 4300);
FORCEPROP 3 LASTPIN (-3500 4300) SIG_NAME M_I_CPU1_SA_DQS_DP<8>
J 0
(-3490 4310);
DISPLAY 0.659574 (-3490 4310);
PAINT MONO (-3490 4310);
DISPLAY INVISIBLE (-3490 4310);
FORCEPROP 1 LASTPIN (-3500 4300) BN 8
J 0
(-3512 4308);
DISPLAY 0.489362 (-3512 4308);
PAINT GREEN (-3512 4308);
FORCEPROP 2 LAST CDS_LIB mstr_standard
J 0
(-3450 4300);
DISPLAY 0.723404 (-3450 4300);
PAINT MONO (-3450 4300);
DISPLAY INVISIBLE (-3450 4300);
FORCEPROP 1 LAST BODY_TYPE PLUMBING
J 0
(-3450 4350);
DISPLAY 0.872340 (-3450 4350);
PAINT GREEN (-3450 4350);
DISPLAY INVISIBLE (-3450 4350);
FORCEPROP 1 LAST HDL_TAP TRUE
J 0
(-3125 4175);
DISPLAY 0.872340 (-3125 4175);
DISPLAY INVISIBLE (-3125 4175);
FORCEPROP 1 LAST PATH I203
J 0
(-3452 4300);
DISPLAY 0.872340 (-3452 4300);
PAINT GREEN (-3452 4300);
DISPLAY INVISIBLE (-3452 4300);
FORCEADD TAP..1
(-3250 4250);
FORCEPROP 3 LASTPIN (-3300 4250) SIG_NAME M_I_CPU1_SA_DQS_DN<8>
J 0
(-3290 4260);
DISPLAY 0.659574 (-3290 4260);
PAINT MONO (-3290 4260);
DISPLAY INVISIBLE (-3290 4260);
FORCEPROP 1 LASTPIN (-3300 4250) BN 8
J 0
(-3312 4258);
DISPLAY 0.489362 (-3312 4258);
PAINT GREEN (-3312 4258);
FORCEPROP 2 LAST CDS_LIB mstr_standard
J 0
(-3250 4250);
DISPLAY 0.723404 (-3250 4250);
PAINT MONO (-3250 4250);
DISPLAY INVISIBLE (-3250 4250);
FORCEPROP 1 LAST BODY_TYPE PLUMBING
J 0
(-3250 4300);
DISPLAY 0.872340 (-3250 4300);
PAINT GREEN (-3250 4300);
DISPLAY INVISIBLE (-3250 4300);
FORCEPROP 1 LAST HDL_TAP TRUE
J 0
(-2925 4125);
DISPLAY 0.872340 (-2925 4125);
DISPLAY INVISIBLE (-2925 4125);
FORCEPROP 1 LAST PATH I204
J 0
(-3252 4250);
DISPLAY 0.872340 (-3252 4250);
PAINT GREEN (-3252 4250);
DISPLAY INVISIBLE (-3252 4250);
FORCEADD TAP..1
(-3250 4150);
FORCEPROP 3 LASTPIN (-3300 4150) SIG_NAME M_I_CPU1_SA_DQS_DN<7>
J 0
(-3290 4160);
DISPLAY 0.659574 (-3290 4160);
PAINT MONO (-3290 4160);
DISPLAY INVISIBLE (-3290 4160);
FORCEPROP 1 LASTPIN (-3300 4150) BN 7
J 0
(-3312 4158);
DISPLAY 0.489362 (-3312 4158);
PAINT GREEN (-3312 4158);
FORCEPROP 2 LAST CDS_LIB mstr_standard
J 0
(-3250 4150);
DISPLAY 0.723404 (-3250 4150);
PAINT MONO (-3250 4150);
DISPLAY INVISIBLE (-3250 4150);
FORCEPROP 1 LAST BODY_TYPE PLUMBING
J 0
(-3250 4200);
DISPLAY 0.872340 (-3250 4200);
PAINT GREEN (-3250 4200);
DISPLAY INVISIBLE (-3250 4200);
FORCEPROP 1 LAST HDL_TAP TRUE
J 0
(-2925 4025);
DISPLAY 0.872340 (-2925 4025);
DISPLAY INVISIBLE (-2925 4025);
FORCEPROP 1 LAST PATH I205
J 0
(-3252 4150);
DISPLAY 0.872340 (-3252 4150);
PAINT GREEN (-3252 4150);
DISPLAY INVISIBLE (-3252 4150);
FORCEADD TAP..1
(-3250 4050);
FORCEPROP 3 LASTPIN (-3300 4050) SIG_NAME M_I_CPU1_SA_DQS_DN<6>
J 0
(-3290 4060);
DISPLAY 0.659574 (-3290 4060);
PAINT MONO (-3290 4060);
DISPLAY INVISIBLE (-3290 4060);
FORCEPROP 1 LASTPIN (-3300 4050) BN 6
J 0
(-3312 4058);
DISPLAY 0.489362 (-3312 4058);
PAINT GREEN (-3312 4058);
FORCEPROP 2 LAST CDS_LIB mstr_standard
J 0
(-3250 4050);
DISPLAY 0.723404 (-3250 4050);
PAINT MONO (-3250 4050);
DISPLAY INVISIBLE (-3250 4050);
FORCEPROP 1 LAST BODY_TYPE PLUMBING
J 0
(-3250 4100);
DISPLAY 0.872340 (-3250 4100);
PAINT GREEN (-3250 4100);
DISPLAY INVISIBLE (-3250 4100);
FORCEPROP 1 LAST HDL_TAP TRUE
J 0
(-2925 3925);
DISPLAY 0.872340 (-2925 3925);
DISPLAY INVISIBLE (-2925 3925);
FORCEPROP 1 LAST PATH I206
J 0
(-3252 4050);
DISPLAY 0.872340 (-3252 4050);
PAINT GREEN (-3252 4050);
DISPLAY INVISIBLE (-3252 4050);
FORCEADD TAP..1
(-3250 3950);
FORCEPROP 3 LASTPIN (-3300 3950) SIG_NAME M_I_CPU1_SA_DQS_DN<5>
J 0
(-3290 3960);
DISPLAY 0.659574 (-3290 3960);
PAINT MONO (-3290 3960);
DISPLAY INVISIBLE (-3290 3960);
FORCEPROP 1 LASTPIN (-3300 3950) BN 5
J 0
(-3312 3958);
DISPLAY 0.489362 (-3312 3958);
PAINT GREEN (-3312 3958);
FORCEPROP 2 LAST CDS_LIB mstr_standard
J 0
(-3250 3950);
DISPLAY 0.723404 (-3250 3950);
PAINT MONO (-3250 3950);
DISPLAY INVISIBLE (-3250 3950);
FORCEPROP 1 LAST BODY_TYPE PLUMBING
J 0
(-3250 4000);
DISPLAY 0.872340 (-3250 4000);
PAINT GREEN (-3250 4000);
DISPLAY INVISIBLE (-3250 4000);
FORCEPROP 1 LAST HDL_TAP TRUE
J 0
(-2925 3825);
DISPLAY 0.872340 (-2925 3825);
DISPLAY INVISIBLE (-2925 3825);
FORCEPROP 1 LAST PATH I207
J 0
(-3252 3950);
DISPLAY 0.872340 (-3252 3950);
PAINT GREEN (-3252 3950);
DISPLAY INVISIBLE (-3252 3950);
FORCEADD TAP..1
(-3250 3850);
FORCEPROP 3 LASTPIN (-3300 3850) SIG_NAME M_I_CPU1_SA_DQS_DN<4>
J 0
(-3290 3860);
DISPLAY 0.659574 (-3290 3860);
PAINT MONO (-3290 3860);
DISPLAY INVISIBLE (-3290 3860);
FORCEPROP 1 LASTPIN (-3300 3850) BN 4
J 0
(-3312 3858);
DISPLAY 0.489362 (-3312 3858);
PAINT GREEN (-3312 3858);
FORCEPROP 2 LAST CDS_LIB mstr_standard
J 0
(-3250 3850);
DISPLAY 0.723404 (-3250 3850);
PAINT MONO (-3250 3850);
DISPLAY INVISIBLE (-3250 3850);
FORCEPROP 1 LAST BODY_TYPE PLUMBING
J 0
(-3250 3900);
DISPLAY 0.872340 (-3250 3900);
PAINT GREEN (-3250 3900);
DISPLAY INVISIBLE (-3250 3900);
FORCEPROP 1 LAST HDL_TAP TRUE
J 0
(-2925 3725);
DISPLAY 0.872340 (-2925 3725);
DISPLAY INVISIBLE (-2925 3725);
FORCEPROP 1 LAST PATH I208
J 0
(-3252 3850);
DISPLAY 0.872340 (-3252 3850);
PAINT GREEN (-3252 3850);
DISPLAY INVISIBLE (-3252 3850);
FORCEADD TAP..1
(-3250 3650);
FORCEPROP 3 LASTPIN (-3300 3650) SIG_NAME M_I_CPU1_SA_DQS_DN<2>
J 0
(-3290 3660);
DISPLAY 0.659574 (-3290 3660);
PAINT MONO (-3290 3660);
DISPLAY INVISIBLE (-3290 3660);
FORCEPROP 1 LASTPIN (-3300 3650) BN 2
J 0
(-3312 3658);
DISPLAY 0.489362 (-3312 3658);
PAINT GREEN (-3312 3658);
FORCEPROP 2 LAST CDS_LIB mstr_standard
J 0
(-3250 3650);
DISPLAY 0.723404 (-3250 3650);
PAINT MONO (-3250 3650);
DISPLAY INVISIBLE (-3250 3650);
FORCEPROP 1 LAST BODY_TYPE PLUMBING
J 0
(-3250 3700);
DISPLAY 0.872340 (-3250 3700);
PAINT GREEN (-3250 3700);
DISPLAY INVISIBLE (-3250 3700);
FORCEPROP 1 LAST HDL_TAP TRUE
J 0
(-2925 3525);
DISPLAY 0.872340 (-2925 3525);
DISPLAY INVISIBLE (-2925 3525);
FORCEPROP 1 LAST PATH I209
J 0
(-3252 3650);
DISPLAY 0.872340 (-3252 3650);
PAINT GREEN (-3252 3650);
DISPLAY INVISIBLE (-3252 3650);
FORCEADD OFFPAGE..1
(-8275 5000);
FORCEPROP 2 LAST $XR0 45 
J 0
(-8526 5000);
DISPLAY 0.638298 (-8526 5000);
PAINT MONO (-8526 5000);
FORCEPROP 2 LAST CDS_LIB mstr_standard
J 0
(-8275 5000);
DISPLAY 0.723404 (-8275 5000);
PAINT MONO (-8275 5000);
DISPLAY INVISIBLE (-8275 5000);
FORCEPROP 1 LAST OFFPAGE TRUE
J 0
(-7950 4875);
DISPLAY 0.872340 (-7950 4875);
PAINT GREEN (-7950 4875);
DISPLAY INVISIBLE (-7950 4875);
FORCEPROP 1 LAST COMMENT_BODY TRUE
J 0
(-8150 4900);
DISPLAY 0.872340 (-8150 4900);
PAINT GREEN (-8150 4900);
DISPLAY INVISIBLE (-8150 4900);
FORCEPROP 2 LAST PATH I21
J 0
(-8525 5050);
DISPLAY 1.021277 (-8525 5050);
DISPLAY INVISIBLE (-8525 5050);
FORCEADD TAP..1
(-3250 3750);
FORCEPROP 3 LASTPIN (-3300 3750) SIG_NAME M_I_CPU1_SA_DQS_DN<3>
J 0
(-3290 3760);
DISPLAY 0.659574 (-3290 3760);
PAINT MONO (-3290 3760);
DISPLAY INVISIBLE (-3290 3760);
FORCEPROP 1 LASTPIN (-3300 3750) BN 3
J 0
(-3312 3758);
DISPLAY 0.489362 (-3312 3758);
PAINT GREEN (-3312 3758);
FORCEPROP 2 LAST CDS_LIB mstr_standard
J 0
(-3250 3750);
DISPLAY 0.723404 (-3250 3750);
PAINT MONO (-3250 3750);
DISPLAY INVISIBLE (-3250 3750);
FORCEPROP 1 LAST BODY_TYPE PLUMBING
J 0
(-3250 3800);
DISPLAY 0.872340 (-3250 3800);
PAINT GREEN (-3250 3800);
DISPLAY INVISIBLE (-3250 3800);
FORCEPROP 1 LAST HDL_TAP TRUE
J 0
(-2925 3625);
DISPLAY 0.872340 (-2925 3625);
DISPLAY INVISIBLE (-2925 3625);
FORCEPROP 1 LAST PATH I210
J 0
(-3252 3750);
DISPLAY 0.872340 (-3252 3750);
PAINT GREEN (-3252 3750);
DISPLAY INVISIBLE (-3252 3750);
FORCEADD TAP..1
(-3450 4200);
FORCEPROP 3 LASTPIN (-3500 4200) SIG_NAME M_I_CPU1_SA_DQS_DP<7>
J 0
(-3490 4210);
DISPLAY 0.659574 (-3490 4210);
PAINT MONO (-3490 4210);
DISPLAY INVISIBLE (-3490 4210);
FORCEPROP 1 LASTPIN (-3500 4200) BN 7
J 0
(-3512 4208);
DISPLAY 0.489362 (-3512 4208);
PAINT GREEN (-3512 4208);
FORCEPROP 2 LAST CDS_LIB mstr_standard
J 0
(-3450 4200);
DISPLAY 0.723404 (-3450 4200);
PAINT MONO (-3450 4200);
DISPLAY INVISIBLE (-3450 4200);
FORCEPROP 1 LAST BODY_TYPE PLUMBING
J 0
(-3450 4250);
DISPLAY 0.872340 (-3450 4250);
PAINT GREEN (-3450 4250);
DISPLAY INVISIBLE (-3450 4250);
FORCEPROP 1 LAST HDL_TAP TRUE
J 0
(-3125 4075);
DISPLAY 0.872340 (-3125 4075);
DISPLAY INVISIBLE (-3125 4075);
FORCEPROP 1 LAST PATH I211
J 0
(-3452 4200);
DISPLAY 0.872340 (-3452 4200);
PAINT GREEN (-3452 4200);
DISPLAY INVISIBLE (-3452 4200);
FORCEADD TAP..1
(-3450 4100);
FORCEPROP 3 LASTPIN (-3500 4100) SIG_NAME M_I_CPU1_SA_DQS_DP<6>
J 0
(-3490 4110);
DISPLAY 0.659574 (-3490 4110);
PAINT MONO (-3490 4110);
DISPLAY INVISIBLE (-3490 4110);
FORCEPROP 1 LASTPIN (-3500 4100) BN 6
J 0
(-3512 4108);
DISPLAY 0.489362 (-3512 4108);
PAINT GREEN (-3512 4108);
FORCEPROP 2 LAST CDS_LIB mstr_standard
J 0
(-3450 4100);
DISPLAY 0.723404 (-3450 4100);
PAINT MONO (-3450 4100);
DISPLAY INVISIBLE (-3450 4100);
FORCEPROP 1 LAST BODY_TYPE PLUMBING
J 0
(-3450 4150);
DISPLAY 0.872340 (-3450 4150);
PAINT GREEN (-3450 4150);
DISPLAY INVISIBLE (-3450 4150);
FORCEPROP 1 LAST HDL_TAP TRUE
J 0
(-3125 3975);
DISPLAY 0.872340 (-3125 3975);
DISPLAY INVISIBLE (-3125 3975);
FORCEPROP 1 LAST PATH I212
J 0
(-3452 4100);
DISPLAY 0.872340 (-3452 4100);
PAINT GREEN (-3452 4100);
DISPLAY INVISIBLE (-3452 4100);
FORCEADD TAP..1
(-3450 3900);
FORCEPROP 3 LASTPIN (-3500 3900) SIG_NAME M_I_CPU1_SA_DQS_DP<4>
J 0
(-3490 3910);
DISPLAY 0.659574 (-3490 3910);
PAINT MONO (-3490 3910);
DISPLAY INVISIBLE (-3490 3910);
FORCEPROP 1 LASTPIN (-3500 3900) BN 4
J 0
(-3512 3908);
DISPLAY 0.489362 (-3512 3908);
PAINT GREEN (-3512 3908);
FORCEPROP 2 LAST CDS_LIB mstr_standard
J 0
(-3450 3900);
DISPLAY 0.723404 (-3450 3900);
PAINT MONO (-3450 3900);
DISPLAY INVISIBLE (-3450 3900);
FORCEPROP 1 LAST BODY_TYPE PLUMBING
J 0
(-3450 3950);
DISPLAY 0.872340 (-3450 3950);
PAINT GREEN (-3450 3950);
DISPLAY INVISIBLE (-3450 3950);
FORCEPROP 1 LAST HDL_TAP TRUE
J 0
(-3125 3775);
DISPLAY 0.872340 (-3125 3775);
DISPLAY INVISIBLE (-3125 3775);
FORCEPROP 1 LAST PATH I213
J 0
(-3452 3900);
DISPLAY 0.872340 (-3452 3900);
PAINT GREEN (-3452 3900);
DISPLAY INVISIBLE (-3452 3900);
FORCEADD TAP..1
(-3450 4000);
FORCEPROP 3 LASTPIN (-3500 4000) SIG_NAME M_I_CPU1_SA_DQS_DP<5>
J 0
(-3490 4010);
DISPLAY 0.659574 (-3490 4010);
PAINT MONO (-3490 4010);
DISPLAY INVISIBLE (-3490 4010);
FORCEPROP 1 LASTPIN (-3500 4000) BN 5
J 0
(-3512 4008);
DISPLAY 0.489362 (-3512 4008);
PAINT GREEN (-3512 4008);
FORCEPROP 2 LAST CDS_LIB mstr_standard
J 0
(-3450 4000);
DISPLAY 0.723404 (-3450 4000);
PAINT MONO (-3450 4000);
DISPLAY INVISIBLE (-3450 4000);
FORCEPROP 1 LAST BODY_TYPE PLUMBING
J 0
(-3450 4050);
DISPLAY 0.872340 (-3450 4050);
PAINT GREEN (-3450 4050);
DISPLAY INVISIBLE (-3450 4050);
FORCEPROP 1 LAST HDL_TAP TRUE
J 0
(-3125 3875);
DISPLAY 0.872340 (-3125 3875);
DISPLAY INVISIBLE (-3125 3875);
FORCEPROP 1 LAST PATH I214
J 0
(-3452 4000);
DISPLAY 0.872340 (-3452 4000);
PAINT GREEN (-3452 4000);
DISPLAY INVISIBLE (-3452 4000);
FORCEADD TAP..1
(-3450 3700);
FORCEPROP 3 LASTPIN (-3500 3700) SIG_NAME M_I_CPU1_SA_DQS_DP<2>
J 0
(-3490 3710);
DISPLAY 0.659574 (-3490 3710);
PAINT MONO (-3490 3710);
DISPLAY INVISIBLE (-3490 3710);
FORCEPROP 1 LASTPIN (-3500 3700) BN 2
J 0
(-3512 3708);
DISPLAY 0.489362 (-3512 3708);
PAINT GREEN (-3512 3708);
FORCEPROP 2 LAST CDS_LIB mstr_standard
J 0
(-3450 3700);
DISPLAY 0.723404 (-3450 3700);
PAINT MONO (-3450 3700);
DISPLAY INVISIBLE (-3450 3700);
FORCEPROP 1 LAST BODY_TYPE PLUMBING
J 0
(-3450 3750);
DISPLAY 0.872340 (-3450 3750);
PAINT GREEN (-3450 3750);
DISPLAY INVISIBLE (-3450 3750);
FORCEPROP 1 LAST HDL_TAP TRUE
J 0
(-3125 3575);
DISPLAY 0.872340 (-3125 3575);
DISPLAY INVISIBLE (-3125 3575);
FORCEPROP 1 LAST PATH I215
J 0
(-3452 3700);
DISPLAY 0.872340 (-3452 3700);
PAINT GREEN (-3452 3700);
DISPLAY INVISIBLE (-3452 3700);
FORCEADD TAP..1
(-3450 3600);
FORCEPROP 3 LASTPIN (-3500 3600) SIG_NAME M_I_CPU1_SA_DQS_DP<1>
J 0
(-3490 3610);
DISPLAY 0.659574 (-3490 3610);
PAINT MONO (-3490 3610);
DISPLAY INVISIBLE (-3490 3610);
FORCEPROP 1 LASTPIN (-3500 3600) BN 1
J 0
(-3512 3608);
DISPLAY 0.489362 (-3512 3608);
PAINT GREEN (-3512 3608);
FORCEPROP 2 LAST CDS_LIB mstr_standard
J 0
(-3450 3600);
DISPLAY 0.723404 (-3450 3600);
PAINT MONO (-3450 3600);
DISPLAY INVISIBLE (-3450 3600);
FORCEPROP 1 LAST BODY_TYPE PLUMBING
J 0
(-3450 3650);
DISPLAY 0.872340 (-3450 3650);
PAINT GREEN (-3450 3650);
DISPLAY INVISIBLE (-3450 3650);
FORCEPROP 1 LAST HDL_TAP TRUE
J 0
(-3125 3475);
DISPLAY 0.872340 (-3125 3475);
DISPLAY INVISIBLE (-3125 3475);
FORCEPROP 1 LAST PATH I216
J 0
(-3452 3600);
DISPLAY 0.872340 (-3452 3600);
PAINT GREEN (-3452 3600);
DISPLAY INVISIBLE (-3452 3600);
FORCEADD TAP..1
(-3450 3500);
FORCEPROP 3 LASTPIN (-3500 3500) SIG_NAME M_I_CPU1_SA_DQS_DP<0>
J 0
(-3490 3510);
DISPLAY 0.659574 (-3490 3510);
PAINT MONO (-3490 3510);
DISPLAY INVISIBLE (-3490 3510);
FORCEPROP 1 LASTPIN (-3500 3500) BN 0
J 0
(-3512 3508);
DISPLAY 0.489362 (-3512 3508);
PAINT GREEN (-3512 3508);
FORCEPROP 2 LAST CDS_LIB mstr_standard
J 0
(-3450 3500);
DISPLAY 0.723404 (-3450 3500);
PAINT MONO (-3450 3500);
DISPLAY INVISIBLE (-3450 3500);
FORCEPROP 1 LAST BODY_TYPE PLUMBING
J 0
(-3450 3550);
DISPLAY 0.872340 (-3450 3550);
PAINT GREEN (-3450 3550);
DISPLAY INVISIBLE (-3450 3550);
FORCEPROP 1 LAST HDL_TAP TRUE
J 0
(-3125 3375);
DISPLAY 0.872340 (-3125 3375);
DISPLAY INVISIBLE (-3125 3375);
FORCEPROP 1 LAST PATH I217
J 0
(-3452 3500);
DISPLAY 0.872340 (-3452 3500);
PAINT GREEN (-3452 3500);
DISPLAY INVISIBLE (-3452 3500);
FORCEADD TAP..1
(-3450 3250);
FORCEPROP 3 LASTPIN (-3500 3250) SIG_NAME M_I_CPU1_SB_DQS_DP<8>
J 0
(-3490 3260);
DISPLAY 0.659574 (-3490 3260);
PAINT MONO (-3490 3260);
DISPLAY INVISIBLE (-3490 3260);
FORCEPROP 1 LASTPIN (-3500 3250) BN 8
J 0
(-3512 3258);
DISPLAY 0.489362 (-3512 3258);
PAINT GREEN (-3512 3258);
FORCEPROP 2 LAST CDS_LIB mstr_standard
J 0
(-3450 3250);
DISPLAY 0.723404 (-3450 3250);
PAINT MONO (-3450 3250);
DISPLAY INVISIBLE (-3450 3250);
FORCEPROP 1 LAST BODY_TYPE PLUMBING
J 0
(-3450 3300);
DISPLAY 0.872340 (-3450 3300);
PAINT GREEN (-3450 3300);
DISPLAY INVISIBLE (-3450 3300);
FORCEPROP 1 LAST HDL_TAP TRUE
J 0
(-3125 3125);
DISPLAY 0.872340 (-3125 3125);
DISPLAY INVISIBLE (-3125 3125);
FORCEPROP 1 LAST PATH I218
J 0
(-3452 3250);
DISPLAY 0.872340 (-3452 3250);
PAINT GREEN (-3452 3250);
DISPLAY INVISIBLE (-3452 3250);
FORCEADD TAP..1
(-3450 3350);
FORCEPROP 3 LASTPIN (-3500 3350) SIG_NAME M_I_CPU1_SB_DQS_DP<9>
J 0
(-3490 3360);
DISPLAY 0.659574 (-3490 3360);
PAINT MONO (-3490 3360);
DISPLAY INVISIBLE (-3490 3360);
FORCEPROP 1 LASTPIN (-3500 3350) BN 9
J 0
(-3512 3358);
DISPLAY 0.489362 (-3512 3358);
PAINT GREEN (-3512 3358);
FORCEPROP 2 LAST CDS_LIB mstr_standard
J 0
(-3450 3350);
DISPLAY 0.723404 (-3450 3350);
PAINT MONO (-3450 3350);
DISPLAY INVISIBLE (-3450 3350);
FORCEPROP 1 LAST BODY_TYPE PLUMBING
J 0
(-3450 3400);
DISPLAY 0.872340 (-3450 3400);
PAINT GREEN (-3450 3400);
DISPLAY INVISIBLE (-3450 3400);
FORCEPROP 1 LAST HDL_TAP TRUE
J 0
(-3125 3225);
DISPLAY 0.872340 (-3125 3225);
DISPLAY INVISIBLE (-3125 3225);
FORCEPROP 1 LAST PATH I219
J 0
(-3452 3350);
DISPLAY 0.872340 (-3452 3350);
PAINT GREEN (-3452 3350);
DISPLAY INVISIBLE (-3452 3350);
FORCEADD SCONN288_DDR506112002KQ..1
(-6825 3600);
FORCEPROP 1 LAST LOCATION J100
J 0
(-7275 5675);
DISPLAY 0.468085 (-7275 5675);
PAINT SKYBLUE (-7275 5675);
FORCEPROP 0 LAST $SEC 1
J 0
(-7275 5825);
DISPLAY 0.680851 (-7275 5825);
PAINT MONO (-7275 5825);
DISPLAY INVISIBLE (-7275 5825);
FORCEPROP 2 LAST CDS_SEC 1
J 0
(-7275 5825);
DISPLAY 1.021277 (-7275 5825);
DISPLAY INVISIBLE (-7275 5825);
FORCEPROP 0 LASTPIN (-7425 3000) $PN 62
J 2
(-7435 3010);
DISPLAY 0.680851 (-7435 3010);
PAINT MONO (-7435 3010);
FORCEPROP 0 LASTPIN (-7425 5050) $PN 66
J 2
(-7435 5060);
DISPLAY 0.680851 (-7435 5060);
PAINT MONO (-7435 5060);
FORCEPROP 0 LASTPIN (-7425 4650) $PN 76
J 2
(-7435 4660);
DISPLAY 0.680851 (-7435 4660);
PAINT MONO (-7435 4660);
FORCEPROP 0 LASTPIN (-7425 5100) $PN 211
J 2
(-7435 5110);
DISPLAY 0.680851 (-7435 5110);
PAINT MONO (-7435 5110);
FORCEPROP 0 LASTPIN (-7425 4700) $PN 221
J 2
(-7435 4710);
DISPLAY 0.680851 (-7435 4710);
PAINT MONO (-7435 4710);
FORCEPROP 0 LASTPIN (-7425 5150) $PN 68
J 2
(-7435 5160);
DISPLAY 0.680851 (-7435 5160);
PAINT MONO (-7435 5160);
FORCEPROP 0 LASTPIN (-7425 4750) $PN 78
J 2
(-7435 4760);
DISPLAY 0.680851 (-7435 4760);
PAINT MONO (-7435 4760);
FORCEPROP 0 LASTPIN (-7425 5200) $PN 213
J 2
(-7435 5210);
DISPLAY 0.680851 (-7435 5210);
PAINT MONO (-7435 5210);
FORCEPROP 0 LASTPIN (-7425 4800) $PN 223
J 2
(-7435 4810);
DISPLAY 0.680851 (-7435 4810);
PAINT MONO (-7435 4810);
FORCEPROP 0 LASTPIN (-7425 5250) $PN 70
J 2
(-7435 5260);
DISPLAY 0.680851 (-7435 5260);
PAINT MONO (-7435 5260);
FORCEPROP 0 LASTPIN (-7425 4850) $PN 80
J 2
(-7435 4860);
DISPLAY 0.680851 (-7435 4860);
PAINT MONO (-7435 4860);
FORCEPROP 0 LASTPIN (-7425 5300) $PN 215
J 2
(-7435 5310);
DISPLAY 0.680851 (-7435 5310);
PAINT MONO (-7435 5310);
FORCEPROP 0 LASTPIN (-7425 4900) $PN 225
J 2
(-7435 4910);
DISPLAY 0.680851 (-7435 4910);
PAINT MONO (-7435 4910);
FORCEPROP 0 LASTPIN (-7425 5350) $PN 72
J 2
(-7435 5360);
DISPLAY 0.680851 (-7435 5360);
PAINT MONO (-7435 5360);
FORCEPROP 0 LASTPIN (-7425 4950) $PN 82
J 2
(-7435 4960);
DISPLAY 0.680851 (-7435 4960);
PAINT MONO (-7435 4960);
FORCEPROP 0 LASTPIN (-7425 3600) $PN 51
J 2
(-7435 3610);
DISPLAY 0.680851 (-7435 3610);
PAINT MONO (-7435 3610);
FORCEPROP 0 LASTPIN (-7425 3150) $PN 96
J 2
(-7435 3160);
DISPLAY 0.680851 (-7435 3160);
PAINT MONO (-7435 3160);
FORCEPROP 0 LASTPIN (-7425 3650) $PN 53
J 2
(-7435 3660);
DISPLAY 0.680851 (-7435 3660);
PAINT MONO (-7435 3660);
FORCEPROP 0 LASTPIN (-7425 3200) $PN 98
J 2
(-7435 3210);
DISPLAY 0.680851 (-7435 3210);
PAINT MONO (-7435 3210);
FORCEPROP 0 LASTPIN (-7425 3700) $PN 196
J 2
(-7435 3710);
DISPLAY 0.680851 (-7435 3710);
PAINT MONO (-7435 3710);
FORCEPROP 0 LASTPIN (-7425 3250) $PN 241
J 2
(-7435 3260);
DISPLAY 0.680851 (-7435 3260);
PAINT MONO (-7435 3260);
FORCEPROP 0 LASTPIN (-7425 3750) $PN 198
J 2
(-7435 3760);
DISPLAY 0.680851 (-7435 3760);
PAINT MONO (-7435 3760);
FORCEPROP 0 LASTPIN (-7425 3300) $PN 243
J 2
(-7435 3310);
DISPLAY 0.680851 (-7435 3310);
PAINT MONO (-7435 3310);
FORCEPROP 0 LASTPIN (-7425 3800) $PN 58
J 2
(-7435 3810);
DISPLAY 0.680851 (-7435 3810);
PAINT MONO (-7435 3810);
FORCEPROP 0 LASTPIN (-7425 3350) $PN 89
J 2
(-7435 3360);
DISPLAY 0.680851 (-7435 3360);
PAINT MONO (-7435 3360);
FORCEPROP 0 LASTPIN (-7425 3850) $PN 60
J 2
(-7435 3860);
DISPLAY 0.680851 (-7435 3860);
PAINT MONO (-7435 3860);
FORCEPROP 0 LASTPIN (-7425 3400) $PN 91
J 2
(-7435 3410);
DISPLAY 0.680851 (-7435 3410);
PAINT MONO (-7435 3410);
FORCEPROP 0 LASTPIN (-7425 3900) $PN 203
J 2
(-7435 3910);
DISPLAY 0.680851 (-7435 3910);
PAINT MONO (-7435 3910);
FORCEPROP 0 LASTPIN (-7425 3450) $PN 234
J 2
(-7435 3460);
DISPLAY 0.680851 (-7435 3460);
PAINT MONO (-7435 3460);
FORCEPROP 0 LASTPIN (-7425 3950) $PN 205
J 2
(-7435 3960);
DISPLAY 0.680851 (-7435 3960);
PAINT MONO (-7435 3960);
FORCEPROP 0 LASTPIN (-7425 3500) $PN 236
J 2
(-7435 3510);
DISPLAY 0.680851 (-7435 3510);
PAINT MONO (-7435 3510);
FORCEPROP 0 LASTPIN (-7425 4050) $PN 218
J 2
(-7435 4060);
DISPLAY 0.680851 (-7435 4060);
PAINT MONO (-7435 4060);
FORCEPROP 0 LASTPIN (-7425 4100) $PN 217
J 2
(-7435 4110);
DISPLAY 0.680851 (-7435 4110);
PAINT MONO (-7435 4110);
FORCEPROP 0 LASTPIN (-7425 4350) $PN 64
J 2
(-7435 4360);
DISPLAY 0.680851 (-7435 4360);
PAINT MONO (-7435 4360);
FORCEPROP 0 LASTPIN (-7425 4200) $PN 84
J 2
(-7435 4210);
DISPLAY 0.680851 (-7435 4210);
PAINT MONO (-7435 4210);
FORCEPROP 0 LASTPIN (-7425 4400) $PN 209
J 2
(-7435 4410);
DISPLAY 0.680851 (-7435 4410);
PAINT MONO (-7435 4410);
FORCEPROP 0 LASTPIN (-7425 4250) $PN 229
J 2
(-7435 4260);
DISPLAY 0.680851 (-7435 4260);
PAINT MONO (-7435 4260);
FORCEPROP 0 LASTPIN (-6225 3800) $PN 7
J 0
(-6215 3810);
DISPLAY 0.680851 (-6215 3810);
PAINT MONO (-6215 3810);
FORCEPROP 0 LASTPIN (-6225 2150) $PN 100
J 0
(-6215 2160);
DISPLAY 0.680851 (-6215 2160);
PAINT MONO (-6215 2160);
FORCEPROP 0 LASTPIN (-6225 3850) $PN 9
J 0
(-6215 3860);
DISPLAY 0.680851 (-6215 3860);
PAINT MONO (-6215 3860);
FORCEPROP 0 LASTPIN (-6225 2200) $PN 102
J 0
(-6215 2210);
DISPLAY 0.680851 (-6215 2210);
PAINT MONO (-6215 2210);
FORCEPROP 0 LASTPIN (-6225 3900) $PN 152
J 0
(-6215 3910);
DISPLAY 0.680851 (-6215 3910);
PAINT MONO (-6215 3910);
FORCEPROP 0 LASTPIN (-6225 2250) $PN 245
J 0
(-6215 2260);
DISPLAY 0.680851 (-6215 2260);
PAINT MONO (-6215 2260);
FORCEPROP 0 LASTPIN (-6225 3950) $PN 154
J 0
(-6215 3960);
DISPLAY 0.680851 (-6215 3960);
PAINT MONO (-6215 3960);
FORCEPROP 0 LASTPIN (-6225 2300) $PN 247
J 0
(-6215 2310);
DISPLAY 0.680851 (-6215 2310);
PAINT MONO (-6215 2310);
FORCEPROP 0 LASTPIN (-6225 4000) $PN 14
J 0
(-6215 4010);
DISPLAY 0.680851 (-6215 4010);
PAINT MONO (-6215 4010);
FORCEPROP 0 LASTPIN (-6225 2350) $PN 107
J 0
(-6215 2360);
DISPLAY 0.680851 (-6215 2360);
PAINT MONO (-6215 2360);
FORCEPROP 0 LASTPIN (-6225 4050) $PN 16
J 0
(-6215 4060);
DISPLAY 0.680851 (-6215 4060);
PAINT MONO (-6215 4060);
FORCEPROP 0 LASTPIN (-6225 2400) $PN 109
J 0
(-6215 2410);
DISPLAY 0.680851 (-6215 2410);
PAINT MONO (-6215 2410);
FORCEPROP 0 LASTPIN (-6225 4100) $PN 159
J 0
(-6215 4110);
DISPLAY 0.680851 (-6215 4110);
PAINT MONO (-6215 4110);
FORCEPROP 0 LASTPIN (-6225 2450) $PN 252
J 0
(-6215 2460);
DISPLAY 0.680851 (-6215 2460);
PAINT MONO (-6215 2460);
FORCEPROP 0 LASTPIN (-6225 4150) $PN 161
J 0
(-6215 4160);
DISPLAY 0.680851 (-6215 4160);
PAINT MONO (-6215 4160);
FORCEPROP 0 LASTPIN (-6225 2500) $PN 254
J 0
(-6215 2510);
DISPLAY 0.680851 (-6215 2510);
PAINT MONO (-6215 2510);
FORCEPROP 0 LASTPIN (-6225 4200) $PN 18
J 0
(-6215 4210);
DISPLAY 0.680851 (-6215 4210);
PAINT MONO (-6215 4210);
FORCEPROP 0 LASTPIN (-6225 2550) $PN 111
J 0
(-6215 2560);
DISPLAY 0.680851 (-6215 2560);
PAINT MONO (-6215 2560);
FORCEPROP 0 LASTPIN (-6225 4250) $PN 20
J 0
(-6215 4260);
DISPLAY 0.680851 (-6215 4260);
PAINT MONO (-6215 4260);
FORCEPROP 0 LASTPIN (-6225 2600) $PN 113
J 0
(-6215 2610);
DISPLAY 0.680851 (-6215 2610);
PAINT MONO (-6215 2610);
FORCEPROP 0 LASTPIN (-6225 4300) $PN 163
J 0
(-6215 4310);
DISPLAY 0.680851 (-6215 4310);
PAINT MONO (-6215 4310);
FORCEPROP 0 LASTPIN (-6225 2650) $PN 256
J 0
(-6215 2660);
DISPLAY 0.680851 (-6215 2660);
PAINT MONO (-6215 2660);
FORCEPROP 0 LASTPIN (-6225 4350) $PN 165
J 0
(-6215 4360);
DISPLAY 0.680851 (-6215 4360);
PAINT MONO (-6215 4360);
FORCEPROP 0 LASTPIN (-6225 2700) $PN 258
J 0
(-6215 2710);
DISPLAY 0.680851 (-6215 2710);
PAINT MONO (-6215 2710);
FORCEPROP 0 LASTPIN (-6225 4400) $PN 25
J 0
(-6215 4410);
DISPLAY 0.680851 (-6215 4410);
PAINT MONO (-6215 4410);
FORCEPROP 0 LASTPIN (-6225 2750) $PN 118
J 0
(-6215 2760);
DISPLAY 0.680851 (-6215 2760);
PAINT MONO (-6215 2760);
FORCEPROP 0 LASTPIN (-6225 4450) $PN 27
J 0
(-6215 4460);
DISPLAY 0.680851 (-6215 4460);
PAINT MONO (-6215 4460);
FORCEPROP 0 LASTPIN (-6225 2800) $PN 120
J 0
(-6215 2810);
DISPLAY 0.680851 (-6215 2810);
PAINT MONO (-6215 2810);
FORCEPROP 0 LASTPIN (-6225 4500) $PN 170
J 0
(-6215 4510);
DISPLAY 0.680851 (-6215 4510);
PAINT MONO (-6215 4510);
FORCEPROP 0 LASTPIN (-6225 2850) $PN 263
J 0
(-6215 2860);
DISPLAY 0.680851 (-6215 2860);
PAINT MONO (-6215 2860);
FORCEPROP 0 LASTPIN (-6225 4550) $PN 172
J 0
(-6215 4560);
DISPLAY 0.680851 (-6215 4560);
PAINT MONO (-6215 4560);
FORCEPROP 0 LASTPIN (-6225 2900) $PN 265
J 0
(-6215 2910);
DISPLAY 0.680851 (-6215 2910);
PAINT MONO (-6215 2910);
FORCEPROP 0 LASTPIN (-6225 4600) $PN 29
J 0
(-6215 4610);
DISPLAY 0.680851 (-6215 4610);
PAINT MONO (-6215 4610);
FORCEPROP 0 LASTPIN (-6225 2950) $PN 122
J 0
(-6215 2960);
DISPLAY 0.680851 (-6215 2960);
PAINT MONO (-6215 2960);
FORCEPROP 0 LASTPIN (-6225 4650) $PN 31
J 0
(-6215 4660);
DISPLAY 0.680851 (-6215 4660);
PAINT MONO (-6215 4660);
FORCEPROP 0 LASTPIN (-6225 3000) $PN 124
J 0
(-6215 3010);
DISPLAY 0.680851 (-6215 3010);
PAINT MONO (-6215 3010);
FORCEPROP 0 LASTPIN (-6225 4700) $PN 174
J 0
(-6215 4710);
DISPLAY 0.680851 (-6215 4710);
PAINT MONO (-6215 4710);
FORCEPROP 0 LASTPIN (-6225 3050) $PN 267
J 0
(-6215 3060);
DISPLAY 0.680851 (-6215 3060);
PAINT MONO (-6215 3060);
FORCEPROP 0 LASTPIN (-6225 4750) $PN 176
J 0
(-6215 4760);
DISPLAY 0.680851 (-6215 4760);
PAINT MONO (-6215 4760);
FORCEPROP 0 LASTPIN (-6225 3100) $PN 269
J 0
(-6215 3110);
DISPLAY 0.680851 (-6215 3110);
PAINT MONO (-6215 3110);
FORCEPROP 0 LASTPIN (-6225 4800) $PN 36
J 0
(-6215 4810);
DISPLAY 0.680851 (-6215 4810);
PAINT MONO (-6215 4810);
FORCEPROP 0 LASTPIN (-6225 3150) $PN 129
J 0
(-6215 3160);
DISPLAY 0.680851 (-6215 3160);
PAINT MONO (-6215 3160);
FORCEPROP 0 LASTPIN (-6225 4850) $PN 38
J 0
(-6215 4860);
DISPLAY 0.680851 (-6215 4860);
PAINT MONO (-6215 4860);
FORCEPROP 0 LASTPIN (-6225 3200) $PN 131
J 0
(-6215 3210);
DISPLAY 0.680851 (-6215 3210);
PAINT MONO (-6215 3210);
FORCEPROP 0 LASTPIN (-6225 4900) $PN 181
J 0
(-6215 4910);
DISPLAY 0.680851 (-6215 4910);
PAINT MONO (-6215 4910);
FORCEPROP 0 LASTPIN (-6225 3250) $PN 274
J 0
(-6215 3260);
DISPLAY 0.680851 (-6215 3260);
PAINT MONO (-6215 3260);
FORCEPROP 0 LASTPIN (-6225 4950) $PN 183
J 0
(-6215 4960);
DISPLAY 0.680851 (-6215 4960);
PAINT MONO (-6215 4960);
FORCEPROP 0 LASTPIN (-6225 3300) $PN 276
J 0
(-6215 3310);
DISPLAY 0.680851 (-6215 3310);
PAINT MONO (-6215 3310);
FORCEPROP 0 LASTPIN (-6225 5000) $PN 40
J 0
(-6215 5010);
DISPLAY 0.680851 (-6215 5010);
PAINT MONO (-6215 5010);
FORCEPROP 0 LASTPIN (-6225 3350) $PN 133
J 0
(-6215 3360);
DISPLAY 0.680851 (-6215 3360);
PAINT MONO (-6215 3360);
FORCEPROP 0 LASTPIN (-6225 5050) $PN 42
J 0
(-6215 5060);
DISPLAY 0.680851 (-6215 5060);
PAINT MONO (-6215 5060);
FORCEPROP 0 LASTPIN (-6225 3400) $PN 135
J 0
(-6215 3410);
DISPLAY 0.680851 (-6215 3410);
PAINT MONO (-6215 3410);
FORCEPROP 0 LASTPIN (-6225 5100) $PN 185
J 0
(-6215 5110);
DISPLAY 0.680851 (-6215 5110);
PAINT MONO (-6215 5110);
FORCEPROP 0 LASTPIN (-6225 3450) $PN 278
J 0
(-6215 3460);
DISPLAY 0.680851 (-6215 3460);
PAINT MONO (-6215 3460);
FORCEPROP 0 LASTPIN (-6225 5150) $PN 187
J 0
(-6215 5160);
DISPLAY 0.680851 (-6215 5160);
PAINT MONO (-6215 5160);
FORCEPROP 0 LASTPIN (-6225 3500) $PN 280
J 0
(-6215 3510);
DISPLAY 0.680851 (-6215 3510);
PAINT MONO (-6215 3510);
FORCEPROP 0 LASTPIN (-6225 5200) $PN 47
J 0
(-6215 5210);
DISPLAY 0.680851 (-6215 5210);
PAINT MONO (-6215 5210);
FORCEPROP 0 LASTPIN (-6225 3550) $PN 140
J 0
(-6215 3560);
DISPLAY 0.680851 (-6215 3560);
PAINT MONO (-6215 3560);
FORCEPROP 0 LASTPIN (-6225 5250) $PN 49
J 0
(-6215 5260);
DISPLAY 0.680851 (-6215 5260);
PAINT MONO (-6215 5260);
FORCEPROP 0 LASTPIN (-6225 3600) $PN 142
J 0
(-6215 3610);
DISPLAY 0.680851 (-6215 3610);
PAINT MONO (-6215 3610);
FORCEPROP 0 LASTPIN (-6225 5300) $PN 192
J 0
(-6215 5310);
DISPLAY 0.680851 (-6215 5310);
PAINT MONO (-6215 5310);
FORCEPROP 0 LASTPIN (-6225 3650) $PN 285
J 0
(-6215 3660);
DISPLAY 0.680851 (-6215 3660);
PAINT MONO (-6215 3660);
FORCEPROP 0 LASTPIN (-6225 5350) $PN 194
J 0
(-6215 5360);
DISPLAY 0.680851 (-6215 5360);
PAINT MONO (-6215 5360);
FORCEPROP 0 LASTPIN (-6225 3700) $PN 287
J 0
(-6215 3710);
DISPLAY 0.680851 (-6215 3710);
PAINT MONO (-6215 3710);
FORCEPROP 0 LASTPIN (-7425 2850) $PN 148
J 2
(-7435 2860);
DISPLAY 0.680851 (-7435 2860);
PAINT MONO (-7435 2860);
FORCEPROP 0 LASTPIN (-7425 2750) $PN 4
J 2
(-7435 2760);
DISPLAY 0.680851 (-7435 2760);
PAINT MONO (-7435 2760);
FORCEPROP 0 LASTPIN (-7425 2800) $PN 5
J 2
(-7435 2810);
DISPLAY 0.680851 (-7435 2810);
PAINT MONO (-7435 2810);
FORCEPROP 0 LASTPIN (-7425 1950) $PN 86
J 2
(-7435 1960);
DISPLAY 0.680851 (-7435 1960);
PAINT MONO (-7435 1960);
FORCEPROP 0 LASTPIN (-7425 1900) $PN 87
J 2
(-7435 1910);
DISPLAY 0.680851 (-7435 1910);
PAINT MONO (-7435 1910);
FORCEPROP 0 LASTPIN (-7425 4550) $PN 74
J 2
(-7435 4560);
DISPLAY 0.680851 (-7435 4560);
PAINT MONO (-7435 4560);
FORCEPROP 0 LASTPIN (-7425 4500) $PN 227
J 2
(-7435 4510);
DISPLAY 0.680851 (-7435 4510);
PAINT MONO (-7435 4510);
FORCEPROP 0 LASTPIN (-7425 2500) $PN 147
J 2
(-7435 2510);
DISPLAY 0.680851 (-7435 2510);
PAINT MONO (-7435 2510);
FORCEPROP 0 LASTPIN (-7425 3050) $PN 207
J 2
(-7435 3060);
DISPLAY 0.680851 (-7435 3060);
PAINT MONO (-7435 3060);
FORCEPROP 0 LASTPIN (-7425 2100) $PN 2
J 2
(-7435 2110);
DISPLAY 0.680851 (-7435 2110);
PAINT MONO (-7435 2110);
FORCEPROP 0 LASTPIN (-7425 2150) $PN 144
J 2
(-7435 2160);
DISPLAY 0.680851 (-7435 2160);
PAINT MONO (-7435 2160);
FORCEPROP 0 LASTPIN (-7425 2200) $PN 149
J 2
(-7435 2210);
DISPLAY 0.680851 (-7435 2210);
PAINT MONO (-7435 2210);
FORCEPROP 0 LASTPIN (-7425 2250) $PN 150
J 2
(-7435 2260);
DISPLAY 0.680851 (-7435 2260);
PAINT MONO (-7435 2260);
FORCEPROP 0 LASTPIN (-7425 2300) $PN 220
J 2
(-7435 2310);
DISPLAY 0.680851 (-7435 2310);
PAINT MONO (-7435 2310);
FORCEPROP 0 LASTPIN (-7425 2350) $PN 231
J 2
(-7435 2360);
DISPLAY 0.680851 (-7435 2360);
PAINT MONO (-7435 2360);
FORCEPROP 0 LASTPIN (-7425 2400) $PN 232
J 2
(-7435 2410);
DISPLAY 0.680851 (-7435 2410);
PAINT MONO (-7435 2410);
FORCEPROP 0 LASTPIN (-7425 2900) $PN 3
J 2
(-7435 2910);
DISPLAY 0.680851 (-7435 2910);
PAINT MONO (-7435 2910);
FORCEPROP 2 LAST PART_TYPE SMLF
J 0
(-7275 5775);
DISPLAY 1.021277 (-7275 5775);
FORCEPROP 1 LAST MATERIAL IO
J 0
(-7275 5525);
DISPLAY 0.468085 (-7275 5525);
PAINT SKYBLUE (-7275 5525);
FORCEPROP 2 LAST VALUE SCONN288_DDR506112002KQ
J 0
(-7275 5725);
DISPLAY 0.489362 (-7275 5725);
PAINT SKYBLUE (-7275 5725);
FORCEPROP 1 LAST CDS_LMAN_SYM_OUTLINE -450,1900,450,-1850
J 0
(-6825 3600);
DISPLAY 0.468085 (-6825 3600);
PAINT GREEN (-6825 3600);
DISPLAY INVISIBLE (-6825 3600);
FORCEPROP 1 LAST NEEDS_NO_SIZE TRUE
J 0
(-6825 3600);
DISPLAY 0.723404 (-6825 3600);
PAINT GREEN (-6825 3600);
DISPLAY INVISIBLE (-6825 3600);
FORCEPROP 2 LAST CDS_LIB pure_quanta
J 0
(-6825 3600);
DISPLAY INVISIBLE (-6825 3600);
FORCEPROP 1 LAST PATH I22
J 0
(-6825 3600);
DISPLAY 0.723404 (-6825 3600);
PAINT GREEN (-6825 3600);
DISPLAY INVISIBLE (-6825 3600);
FORCEPROP 1 LAST PART_NUMBER DFHST8FS479
J 0
(-7275 5600);
DISPLAY 0.468085 (-7275 5600);
PAINT SKYBLUE (-7275 5600);
DISPLAY INVISIBLE (-7275 5600);
FORCEADD TAP..1
(-3250 3200);
FORCEPROP 3 LASTPIN (-3300 3200) SIG_NAME M_I_CPU1_SB_DQS_DN<8>
J 0
(-3290 3210);
DISPLAY 0.659574 (-3290 3210);
PAINT MONO (-3290 3210);
DISPLAY INVISIBLE (-3290 3210);
FORCEPROP 1 LASTPIN (-3300 3200) BN 8
J 0
(-3312 3208);
DISPLAY 0.489362 (-3312 3208);
PAINT GREEN (-3312 3208);
FORCEPROP 2 LAST CDS_LIB mstr_standard
J 0
(-3250 3200);
DISPLAY 0.723404 (-3250 3200);
PAINT MONO (-3250 3200);
DISPLAY INVISIBLE (-3250 3200);
FORCEPROP 1 LAST BODY_TYPE PLUMBING
J 0
(-3250 3250);
DISPLAY 0.872340 (-3250 3250);
PAINT GREEN (-3250 3250);
DISPLAY INVISIBLE (-3250 3250);
FORCEPROP 1 LAST HDL_TAP TRUE
J 0
(-2925 3075);
DISPLAY 0.872340 (-2925 3075);
DISPLAY INVISIBLE (-2925 3075);
FORCEPROP 1 LAST PATH I220
J 0
(-3252 3200);
DISPLAY 0.872340 (-3252 3200);
PAINT GREEN (-3252 3200);
DISPLAY INVISIBLE (-3252 3200);
FORCEADD TAP..1
(-3250 3000);
FORCEPROP 3 LASTPIN (-3300 3000) SIG_NAME M_I_CPU1_SB_DQS_DN<6>
J 0
(-3290 3010);
DISPLAY 0.659574 (-3290 3010);
PAINT MONO (-3290 3010);
DISPLAY INVISIBLE (-3290 3010);
FORCEPROP 1 LASTPIN (-3300 3000) BN 6
J 0
(-3312 3008);
DISPLAY 0.489362 (-3312 3008);
PAINT GREEN (-3312 3008);
FORCEPROP 2 LAST CDS_LIB mstr_standard
J 0
(-3250 3000);
DISPLAY 0.723404 (-3250 3000);
PAINT MONO (-3250 3000);
DISPLAY INVISIBLE (-3250 3000);
FORCEPROP 1 LAST BODY_TYPE PLUMBING
J 0
(-3250 3050);
DISPLAY 0.872340 (-3250 3050);
PAINT GREEN (-3250 3050);
DISPLAY INVISIBLE (-3250 3050);
FORCEPROP 1 LAST HDL_TAP TRUE
J 0
(-2925 2875);
DISPLAY 0.872340 (-2925 2875);
DISPLAY INVISIBLE (-2925 2875);
FORCEPROP 1 LAST PATH I221
J 0
(-3252 3000);
DISPLAY 0.872340 (-3252 3000);
PAINT GREEN (-3252 3000);
DISPLAY INVISIBLE (-3252 3000);
FORCEADD TAP..1
(-3250 2900);
FORCEPROP 3 LASTPIN (-3300 2900) SIG_NAME M_I_CPU1_SB_DQS_DN<5>
J 0
(-3290 2910);
DISPLAY 0.659574 (-3290 2910);
PAINT MONO (-3290 2910);
DISPLAY INVISIBLE (-3290 2910);
FORCEPROP 1 LASTPIN (-3300 2900) BN 5
J 0
(-3312 2908);
DISPLAY 0.489362 (-3312 2908);
PAINT GREEN (-3312 2908);
FORCEPROP 2 LAST CDS_LIB mstr_standard
J 0
(-3250 2900);
DISPLAY 0.723404 (-3250 2900);
PAINT MONO (-3250 2900);
DISPLAY INVISIBLE (-3250 2900);
FORCEPROP 1 LAST BODY_TYPE PLUMBING
J 0
(-3250 2950);
DISPLAY 0.872340 (-3250 2950);
PAINT GREEN (-3250 2950);
DISPLAY INVISIBLE (-3250 2950);
FORCEPROP 1 LAST HDL_TAP TRUE
J 0
(-2925 2775);
DISPLAY 0.872340 (-2925 2775);
DISPLAY INVISIBLE (-2925 2775);
FORCEPROP 1 LAST PATH I222
J 0
(-3252 2900);
DISPLAY 0.872340 (-3252 2900);
PAINT GREEN (-3252 2900);
DISPLAY INVISIBLE (-3252 2900);
FORCEADD TAP..1
(-3250 2800);
FORCEPROP 3 LASTPIN (-3300 2800) SIG_NAME M_I_CPU1_SB_DQS_DN<4>
J 0
(-3290 2810);
DISPLAY 0.659574 (-3290 2810);
PAINT MONO (-3290 2810);
DISPLAY INVISIBLE (-3290 2810);
FORCEPROP 1 LASTPIN (-3300 2800) BN 4
J 0
(-3312 2808);
DISPLAY 0.489362 (-3312 2808);
PAINT GREEN (-3312 2808);
FORCEPROP 2 LAST CDS_LIB mstr_standard
J 0
(-3250 2800);
DISPLAY 0.723404 (-3250 2800);
PAINT MONO (-3250 2800);
DISPLAY INVISIBLE (-3250 2800);
FORCEPROP 1 LAST BODY_TYPE PLUMBING
J 0
(-3250 2850);
DISPLAY 0.872340 (-3250 2850);
PAINT GREEN (-3250 2850);
DISPLAY INVISIBLE (-3250 2850);
FORCEPROP 1 LAST HDL_TAP TRUE
J 0
(-2925 2675);
DISPLAY 0.872340 (-2925 2675);
DISPLAY INVISIBLE (-2925 2675);
FORCEPROP 1 LAST PATH I223
J 0
(-3252 2800);
DISPLAY 0.872340 (-3252 2800);
PAINT GREEN (-3252 2800);
DISPLAY INVISIBLE (-3252 2800);
FORCEADD TAP..1
(-3250 2700);
FORCEPROP 3 LASTPIN (-3300 2700) SIG_NAME M_I_CPU1_SB_DQS_DN<3>
J 0
(-3290 2710);
DISPLAY 0.659574 (-3290 2710);
PAINT MONO (-3290 2710);
DISPLAY INVISIBLE (-3290 2710);
FORCEPROP 1 LASTPIN (-3300 2700) BN 3
J 0
(-3312 2708);
DISPLAY 0.489362 (-3312 2708);
PAINT GREEN (-3312 2708);
FORCEPROP 2 LAST CDS_LIB mstr_standard
J 0
(-3250 2700);
DISPLAY 0.723404 (-3250 2700);
PAINT MONO (-3250 2700);
DISPLAY INVISIBLE (-3250 2700);
FORCEPROP 1 LAST BODY_TYPE PLUMBING
J 0
(-3250 2750);
DISPLAY 0.872340 (-3250 2750);
PAINT GREEN (-3250 2750);
DISPLAY INVISIBLE (-3250 2750);
FORCEPROP 1 LAST HDL_TAP TRUE
J 0
(-2925 2575);
DISPLAY 0.872340 (-2925 2575);
DISPLAY INVISIBLE (-2925 2575);
FORCEPROP 1 LAST PATH I224
J 0
(-3252 2700);
DISPLAY 0.872340 (-3252 2700);
PAINT GREEN (-3252 2700);
DISPLAY INVISIBLE (-3252 2700);
FORCEADD TAP..1
(-3250 2600);
FORCEPROP 3 LASTPIN (-3300 2600) SIG_NAME M_I_CPU1_SB_DQS_DN<2>
J 0
(-3290 2610);
DISPLAY 0.659574 (-3290 2610);
PAINT MONO (-3290 2610);
DISPLAY INVISIBLE (-3290 2610);
FORCEPROP 1 LASTPIN (-3300 2600) BN 2
J 0
(-3312 2608);
DISPLAY 0.489362 (-3312 2608);
PAINT GREEN (-3312 2608);
FORCEPROP 2 LAST CDS_LIB mstr_standard
J 0
(-3250 2600);
DISPLAY 0.723404 (-3250 2600);
PAINT MONO (-3250 2600);
DISPLAY INVISIBLE (-3250 2600);
FORCEPROP 1 LAST BODY_TYPE PLUMBING
J 0
(-3250 2650);
DISPLAY 0.872340 (-3250 2650);
PAINT GREEN (-3250 2650);
DISPLAY INVISIBLE (-3250 2650);
FORCEPROP 1 LAST HDL_TAP TRUE
J 0
(-2925 2475);
DISPLAY 0.872340 (-2925 2475);
DISPLAY INVISIBLE (-2925 2475);
FORCEPROP 1 LAST PATH I225
J 0
(-3252 2600);
DISPLAY 0.872340 (-3252 2600);
PAINT GREEN (-3252 2600);
DISPLAY INVISIBLE (-3252 2600);
FORCEADD TAP..1
(-3250 2500);
FORCEPROP 3 LASTPIN (-3300 2500) SIG_NAME M_I_CPU1_SB_DQS_DN<1>
J 0
(-3290 2510);
DISPLAY 0.659574 (-3290 2510);
PAINT MONO (-3290 2510);
DISPLAY INVISIBLE (-3290 2510);
FORCEPROP 1 LASTPIN (-3300 2500) BN 1
J 0
(-3312 2508);
DISPLAY 0.489362 (-3312 2508);
PAINT GREEN (-3312 2508);
FORCEPROP 2 LAST CDS_LIB mstr_standard
J 0
(-3250 2500);
DISPLAY 0.723404 (-3250 2500);
PAINT MONO (-3250 2500);
DISPLAY INVISIBLE (-3250 2500);
FORCEPROP 1 LAST BODY_TYPE PLUMBING
J 0
(-3250 2550);
DISPLAY 0.872340 (-3250 2550);
PAINT GREEN (-3250 2550);
DISPLAY INVISIBLE (-3250 2550);
FORCEPROP 1 LAST HDL_TAP TRUE
J 0
(-2925 2375);
DISPLAY 0.872340 (-2925 2375);
DISPLAY INVISIBLE (-2925 2375);
FORCEPROP 1 LAST PATH I226
J 0
(-3252 2500);
DISPLAY 0.872340 (-3252 2500);
PAINT GREEN (-3252 2500);
DISPLAY INVISIBLE (-3252 2500);
FORCEADD TAP..1
(-3250 2400);
FORCEPROP 3 LASTPIN (-3300 2400) SIG_NAME M_I_CPU1_SB_DQS_DN<0>
J 0
(-3290 2410);
DISPLAY 0.659574 (-3290 2410);
PAINT MONO (-3290 2410);
DISPLAY INVISIBLE (-3290 2410);
FORCEPROP 1 LASTPIN (-3300 2400) BN 0
J 0
(-3312 2408);
DISPLAY 0.489362 (-3312 2408);
PAINT GREEN (-3312 2408);
FORCEPROP 2 LAST CDS_LIB mstr_standard
J 0
(-3250 2400);
DISPLAY 0.723404 (-3250 2400);
PAINT MONO (-3250 2400);
DISPLAY INVISIBLE (-3250 2400);
FORCEPROP 1 LAST BODY_TYPE PLUMBING
J 0
(-3250 2450);
DISPLAY 0.872340 (-3250 2450);
PAINT GREEN (-3250 2450);
DISPLAY INVISIBLE (-3250 2450);
FORCEPROP 1 LAST HDL_TAP TRUE
J 0
(-2925 2275);
DISPLAY 0.872340 (-2925 2275);
DISPLAY INVISIBLE (-2925 2275);
FORCEPROP 1 LAST PATH I227
J 0
(-3252 2400);
DISPLAY 0.872340 (-3252 2400);
PAINT GREEN (-3252 2400);
DISPLAY INVISIBLE (-3252 2400);
FORCEADD TAP..1
(-3450 3150);
FORCEPROP 3 LASTPIN (-3500 3150) SIG_NAME M_I_CPU1_SB_DQS_DP<7>
J 0
(-3490 3160);
DISPLAY 0.659574 (-3490 3160);
PAINT MONO (-3490 3160);
DISPLAY INVISIBLE (-3490 3160);
FORCEPROP 1 LASTPIN (-3500 3150) BN 7
J 0
(-3512 3158);
DISPLAY 0.489362 (-3512 3158);
PAINT GREEN (-3512 3158);
FORCEPROP 2 LAST CDS_LIB mstr_standard
J 0
(-3450 3150);
DISPLAY 0.723404 (-3450 3150);
PAINT MONO (-3450 3150);
DISPLAY INVISIBLE (-3450 3150);
FORCEPROP 1 LAST BODY_TYPE PLUMBING
J 0
(-3450 3200);
DISPLAY 0.872340 (-3450 3200);
PAINT GREEN (-3450 3200);
DISPLAY INVISIBLE (-3450 3200);
FORCEPROP 1 LAST HDL_TAP TRUE
J 0
(-3125 3025);
DISPLAY 0.872340 (-3125 3025);
DISPLAY INVISIBLE (-3125 3025);
FORCEPROP 1 LAST PATH I228
J 0
(-3452 3150);
DISPLAY 0.872340 (-3452 3150);
PAINT GREEN (-3452 3150);
DISPLAY INVISIBLE (-3452 3150);
FORCEADD TAP..1
(-3450 3050);
FORCEPROP 3 LASTPIN (-3500 3050) SIG_NAME M_I_CPU1_SB_DQS_DP<6>
J 0
(-3490 3060);
DISPLAY 0.659574 (-3490 3060);
PAINT MONO (-3490 3060);
DISPLAY INVISIBLE (-3490 3060);
FORCEPROP 1 LASTPIN (-3500 3050) BN 6
J 0
(-3512 3058);
DISPLAY 0.489362 (-3512 3058);
PAINT GREEN (-3512 3058);
FORCEPROP 2 LAST CDS_LIB mstr_standard
J 0
(-3450 3050);
DISPLAY 0.723404 (-3450 3050);
PAINT MONO (-3450 3050);
DISPLAY INVISIBLE (-3450 3050);
FORCEPROP 1 LAST BODY_TYPE PLUMBING
J 0
(-3450 3100);
DISPLAY 0.872340 (-3450 3100);
PAINT GREEN (-3450 3100);
DISPLAY INVISIBLE (-3450 3100);
FORCEPROP 1 LAST HDL_TAP TRUE
J 0
(-3125 2925);
DISPLAY 0.872340 (-3125 2925);
DISPLAY INVISIBLE (-3125 2925);
FORCEPROP 1 LAST PATH I229
J 0
(-3452 3050);
DISPLAY 0.872340 (-3452 3050);
PAINT GREEN (-3452 3050);
DISPLAY INVISIBLE (-3452 3050);
FORCEADD TAP..1
R 2
(-7675 3150);
FORCEPROP 3 LASTPIN (-7625 3150) SIG_NAME M_I_CPU1_SB_CB<0>
J 0
(-7615 3160);
DISPLAY 0.659574 (-7615 3160);
PAINT MONO (-7615 3160);
DISPLAY INVISIBLE (-7615 3160);
FORCEPROP 1 LASTPIN (-7625 3150) BN 0
J 2
(-7613 3158);
DISPLAY 0.489362 (-7613 3158);
PAINT GREEN (-7613 3158);
FORCEPROP 2 LAST CDS_LIB mstr_standard
J 0
(-7675 3150);
DISPLAY 0.723404 (-7675 3150);
PAINT MONO (-7675 3150);
DISPLAY INVISIBLE (-7675 3150);
FORCEPROP 1 LAST BODY_TYPE PLUMBING
J 2
(-7675 3200);
DISPLAY 0.872340 (-7675 3200);
PAINT GREEN (-7675 3200);
DISPLAY INVISIBLE (-7675 3200);
FORCEPROP 1 LAST HDL_TAP TRUE
J 2
(-8000 3025);
DISPLAY 0.872340 (-8000 3025);
DISPLAY INVISIBLE (-8000 3025);
FORCEPROP 1 LAST PATH I23
J 2
(-7673 3150);
DISPLAY 0.872340 (-7673 3150);
PAINT GREEN (-7673 3150);
DISPLAY INVISIBLE (-7673 3150);
FORCEADD TAP..1
(-3450 2950);
FORCEPROP 3 LASTPIN (-3500 2950) SIG_NAME M_I_CPU1_SB_DQS_DP<5>
J 0
(-3490 2960);
DISPLAY 0.659574 (-3490 2960);
PAINT MONO (-3490 2960);
DISPLAY INVISIBLE (-3490 2960);
FORCEPROP 1 LASTPIN (-3500 2950) BN 5
J 0
(-3512 2958);
DISPLAY 0.489362 (-3512 2958);
PAINT GREEN (-3512 2958);
FORCEPROP 2 LAST CDS_LIB mstr_standard
J 0
(-3450 2950);
DISPLAY 0.723404 (-3450 2950);
PAINT MONO (-3450 2950);
DISPLAY INVISIBLE (-3450 2950);
FORCEPROP 1 LAST BODY_TYPE PLUMBING
J 0
(-3450 3000);
DISPLAY 0.872340 (-3450 3000);
PAINT GREEN (-3450 3000);
DISPLAY INVISIBLE (-3450 3000);
FORCEPROP 1 LAST HDL_TAP TRUE
J 0
(-3125 2825);
DISPLAY 0.872340 (-3125 2825);
DISPLAY INVISIBLE (-3125 2825);
FORCEPROP 1 LAST PATH I230
J 0
(-3452 2950);
DISPLAY 0.872340 (-3452 2950);
PAINT GREEN (-3452 2950);
DISPLAY INVISIBLE (-3452 2950);
FORCEADD TAP..1
(-3450 2750);
FORCEPROP 3 LASTPIN (-3500 2750) SIG_NAME M_I_CPU1_SB_DQS_DP<3>
J 0
(-3490 2760);
DISPLAY 0.659574 (-3490 2760);
PAINT MONO (-3490 2760);
DISPLAY INVISIBLE (-3490 2760);
FORCEPROP 1 LASTPIN (-3500 2750) BN 3
J 0
(-3512 2758);
DISPLAY 0.489362 (-3512 2758);
PAINT GREEN (-3512 2758);
FORCEPROP 2 LAST CDS_LIB mstr_standard
J 0
(-3450 2750);
DISPLAY 0.723404 (-3450 2750);
PAINT MONO (-3450 2750);
DISPLAY INVISIBLE (-3450 2750);
FORCEPROP 1 LAST BODY_TYPE PLUMBING
J 0
(-3450 2800);
DISPLAY 0.872340 (-3450 2800);
PAINT GREEN (-3450 2800);
DISPLAY INVISIBLE (-3450 2800);
FORCEPROP 1 LAST HDL_TAP TRUE
J 0
(-3125 2625);
DISPLAY 0.872340 (-3125 2625);
DISPLAY INVISIBLE (-3125 2625);
FORCEPROP 1 LAST PATH I231
J 0
(-3452 2750);
DISPLAY 0.872340 (-3452 2750);
PAINT GREEN (-3452 2750);
DISPLAY INVISIBLE (-3452 2750);
FORCEADD TAP..1
(-3450 2850);
FORCEPROP 3 LASTPIN (-3500 2850) SIG_NAME M_I_CPU1_SB_DQS_DP<4>
J 0
(-3490 2860);
DISPLAY 0.659574 (-3490 2860);
PAINT MONO (-3490 2860);
DISPLAY INVISIBLE (-3490 2860);
FORCEPROP 1 LASTPIN (-3500 2850) BN 4
J 0
(-3512 2858);
DISPLAY 0.489362 (-3512 2858);
PAINT GREEN (-3512 2858);
FORCEPROP 2 LAST CDS_LIB mstr_standard
J 0
(-3450 2850);
DISPLAY 0.723404 (-3450 2850);
PAINT MONO (-3450 2850);
DISPLAY INVISIBLE (-3450 2850);
FORCEPROP 1 LAST BODY_TYPE PLUMBING
J 0
(-3450 2900);
DISPLAY 0.872340 (-3450 2900);
PAINT GREEN (-3450 2900);
DISPLAY INVISIBLE (-3450 2900);
FORCEPROP 1 LAST HDL_TAP TRUE
J 0
(-3125 2725);
DISPLAY 0.872340 (-3125 2725);
DISPLAY INVISIBLE (-3125 2725);
FORCEPROP 1 LAST PATH I232
J 0
(-3452 2850);
DISPLAY 0.872340 (-3452 2850);
PAINT GREEN (-3452 2850);
DISPLAY INVISIBLE (-3452 2850);
FORCEADD TAP..1
(-3450 2650);
FORCEPROP 3 LASTPIN (-3500 2650) SIG_NAME M_I_CPU1_SB_DQS_DP<2>
J 0
(-3490 2660);
DISPLAY 0.659574 (-3490 2660);
PAINT MONO (-3490 2660);
DISPLAY INVISIBLE (-3490 2660);
FORCEPROP 1 LASTPIN (-3500 2650) BN 2
J 0
(-3512 2658);
DISPLAY 0.489362 (-3512 2658);
PAINT GREEN (-3512 2658);
FORCEPROP 2 LAST CDS_LIB mstr_standard
J 0
(-3450 2650);
DISPLAY 0.723404 (-3450 2650);
PAINT MONO (-3450 2650);
DISPLAY INVISIBLE (-3450 2650);
FORCEPROP 1 LAST BODY_TYPE PLUMBING
J 0
(-3450 2700);
DISPLAY 0.872340 (-3450 2700);
PAINT GREEN (-3450 2700);
DISPLAY INVISIBLE (-3450 2700);
FORCEPROP 1 LAST HDL_TAP TRUE
J 0
(-3125 2525);
DISPLAY 0.872340 (-3125 2525);
DISPLAY INVISIBLE (-3125 2525);
FORCEPROP 1 LAST PATH I233
J 0
(-3452 2650);
DISPLAY 0.872340 (-3452 2650);
PAINT GREEN (-3452 2650);
DISPLAY INVISIBLE (-3452 2650);
FORCEADD TAP..1
(-3450 2550);
FORCEPROP 3 LASTPIN (-3500 2550) SIG_NAME M_I_CPU1_SB_DQS_DP<1>
J 0
(-3490 2560);
DISPLAY 0.659574 (-3490 2560);
PAINT MONO (-3490 2560);
DISPLAY INVISIBLE (-3490 2560);
FORCEPROP 1 LASTPIN (-3500 2550) BN 1
J 0
(-3512 2558);
DISPLAY 0.489362 (-3512 2558);
PAINT GREEN (-3512 2558);
FORCEPROP 2 LAST CDS_LIB mstr_standard
J 0
(-3450 2550);
DISPLAY 0.723404 (-3450 2550);
PAINT MONO (-3450 2550);
DISPLAY INVISIBLE (-3450 2550);
FORCEPROP 1 LAST BODY_TYPE PLUMBING
J 0
(-3450 2600);
DISPLAY 0.872340 (-3450 2600);
PAINT GREEN (-3450 2600);
DISPLAY INVISIBLE (-3450 2600);
FORCEPROP 1 LAST HDL_TAP TRUE
J 0
(-3125 2425);
DISPLAY 0.872340 (-3125 2425);
DISPLAY INVISIBLE (-3125 2425);
FORCEPROP 1 LAST PATH I234
J 0
(-3452 2550);
DISPLAY 0.872340 (-3452 2550);
PAINT GREEN (-3452 2550);
DISPLAY INVISIBLE (-3452 2550);
FORCEADD TAP..1
(-3450 2450);
FORCEPROP 3 LASTPIN (-3500 2450) SIG_NAME M_I_CPU1_SB_DQS_DP<0>
J 0
(-3490 2460);
DISPLAY 0.659574 (-3490 2460);
PAINT MONO (-3490 2460);
DISPLAY INVISIBLE (-3490 2460);
FORCEPROP 1 LASTPIN (-3500 2450) BN 0
J 0
(-3512 2458);
DISPLAY 0.489362 (-3512 2458);
PAINT GREEN (-3512 2458);
FORCEPROP 2 LAST CDS_LIB mstr_standard
J 0
(-3450 2450);
DISPLAY 0.723404 (-3450 2450);
PAINT MONO (-3450 2450);
DISPLAY INVISIBLE (-3450 2450);
FORCEPROP 1 LAST BODY_TYPE PLUMBING
J 0
(-3450 2500);
DISPLAY 0.872340 (-3450 2500);
PAINT GREEN (-3450 2500);
DISPLAY INVISIBLE (-3450 2500);
FORCEPROP 1 LAST HDL_TAP TRUE
J 0
(-3125 2325);
DISPLAY 0.872340 (-3125 2325);
DISPLAY INVISIBLE (-3125 2325);
FORCEPROP 1 LAST PATH I235
J 0
(-3452 2450);
DISPLAY 0.872340 (-3452 2450);
PAINT GREEN (-3452 2450);
DISPLAY INVISIBLE (-3452 2450);
FORCEADD SCONN288_DDR506112002KQ..2
(-4400 3400);
FORCEPROP 1 LAST LOCATION J100
J 0
(-5000 4725);
DISPLAY 0.468085 (-5000 4725);
PAINT SKYBLUE (-5000 4725);
FORCEPROP 0 LAST $SEC 2
J 0
(-4850 4875);
DISPLAY 0.680851 (-4850 4875);
PAINT MONO (-4850 4875);
DISPLAY INVISIBLE (-4850 4875);
FORCEPROP 0 LAST CDS_SEC 2
J 0
(-4850 4875);
DISPLAY 1.021277 (-4850 4875);
DISPLAY INVISIBLE (-4850 4875);
FORCEPROP 0 LASTPIN (-3650 3450) $PN 12
J 0
(-3640 3460);
DISPLAY 0.680851 (-3640 3460);
PAINT MONO (-3640 3460);
FORCEPROP 0 LASTPIN (-3650 3500) $PN 11
J 0
(-3640 3510);
DISPLAY 0.680851 (-3640 3510);
PAINT MONO (-3640 3510);
FORCEPROP 0 LASTPIN (-3650 2400) $PN 105
J 0
(-3640 2410);
DISPLAY 0.680851 (-3640 2410);
PAINT MONO (-3640 2410);
FORCEPROP 0 LASTPIN (-3650 2450) $PN 104
J 0
(-3640 2460);
DISPLAY 0.680851 (-3640 2460);
PAINT MONO (-3640 2460);
FORCEPROP 0 LASTPIN (-3650 3550) $PN 23
J 0
(-3640 3560);
DISPLAY 0.680851 (-3640 3560);
PAINT MONO (-3640 3560);
FORCEPROP 0 LASTPIN (-3650 3600) $PN 22
J 0
(-3640 3610);
DISPLAY 0.680851 (-3640 3610);
PAINT MONO (-3640 3610);
FORCEPROP 0 LASTPIN (-3650 2500) $PN 116
J 0
(-3640 2510);
DISPLAY 0.680851 (-3640 2510);
PAINT MONO (-3640 2510);
FORCEPROP 0 LASTPIN (-3650 2550) $PN 115
J 0
(-3640 2560);
DISPLAY 0.680851 (-3640 2560);
PAINT MONO (-3640 2560);
FORCEPROP 0 LASTPIN (-3650 3650) $PN 34
J 0
(-3640 3660);
DISPLAY 0.680851 (-3640 3660);
PAINT MONO (-3640 3660);
FORCEPROP 0 LASTPIN (-3650 3700) $PN 33
J 0
(-3640 3710);
DISPLAY 0.680851 (-3640 3710);
PAINT MONO (-3640 3710);
FORCEPROP 0 LASTPIN (-3650 2600) $PN 127
J 0
(-3640 2610);
DISPLAY 0.680851 (-3640 2610);
PAINT MONO (-3640 2610);
FORCEPROP 0 LASTPIN (-3650 2650) $PN 126
J 0
(-3640 2660);
DISPLAY 0.680851 (-3640 2660);
PAINT MONO (-3640 2660);
FORCEPROP 0 LASTPIN (-3650 3750) $PN 45
J 0
(-3640 3760);
DISPLAY 0.680851 (-3640 3760);
PAINT MONO (-3640 3760);
FORCEPROP 0 LASTPIN (-3650 3800) $PN 44
J 0
(-3640 3810);
DISPLAY 0.680851 (-3640 3810);
PAINT MONO (-3640 3810);
FORCEPROP 0 LASTPIN (-3650 2700) $PN 138
J 0
(-3640 2710);
DISPLAY 0.680851 (-3640 2710);
PAINT MONO (-3640 2710);
FORCEPROP 0 LASTPIN (-3650 2750) $PN 137
J 0
(-3640 2760);
DISPLAY 0.680851 (-3640 2760);
PAINT MONO (-3640 2760);
FORCEPROP 0 LASTPIN (-3650 3850) $PN 56
J 0
(-3640 3860);
DISPLAY 0.680851 (-3640 3860);
PAINT MONO (-3640 3860);
FORCEPROP 0 LASTPIN (-3650 3900) $PN 55
J 0
(-3640 3910);
DISPLAY 0.680851 (-3640 3910);
PAINT MONO (-3640 3910);
FORCEPROP 0 LASTPIN (-3650 2800) $PN 238
J 0
(-3640 2810);
DISPLAY 0.680851 (-3640 2810);
PAINT MONO (-3640 2810);
FORCEPROP 0 LASTPIN (-3650 2850) $PN 239
J 0
(-3640 2860);
DISPLAY 0.680851 (-3640 2860);
PAINT MONO (-3640 2860);
FORCEPROP 0 LASTPIN (-3650 3950) $PN 156
J 0
(-3640 3960);
DISPLAY 0.680851 (-3640 3960);
PAINT MONO (-3640 3960);
FORCEPROP 0 LASTPIN (-3650 4000) $PN 157
J 0
(-3640 4010);
DISPLAY 0.680851 (-3640 4010);
PAINT MONO (-3640 4010);
FORCEPROP 0 LASTPIN (-3650 2900) $PN 249
J 0
(-3640 2910);
DISPLAY 0.680851 (-3640 2910);
PAINT MONO (-3640 2910);
FORCEPROP 0 LASTPIN (-3650 2950) $PN 250
J 0
(-3640 2960);
DISPLAY 0.680851 (-3640 2960);
PAINT MONO (-3640 2960);
FORCEPROP 0 LASTPIN (-3650 4050) $PN 167
J 0
(-3640 4060);
DISPLAY 0.680851 (-3640 4060);
PAINT MONO (-3640 4060);
FORCEPROP 0 LASTPIN (-3650 4100) $PN 168
J 0
(-3640 4110);
DISPLAY 0.680851 (-3640 4110);
PAINT MONO (-3640 4110);
FORCEPROP 0 LASTPIN (-3650 3000) $PN 260
J 0
(-3640 3010);
DISPLAY 0.680851 (-3640 3010);
PAINT MONO (-3640 3010);
FORCEPROP 0 LASTPIN (-3650 3050) $PN 261
J 0
(-3640 3060);
DISPLAY 0.680851 (-3640 3060);
PAINT MONO (-3640 3060);
FORCEPROP 0 LASTPIN (-3650 4150) $PN 178
J 0
(-3640 4160);
DISPLAY 0.680851 (-3640 4160);
PAINT MONO (-3640 4160);
FORCEPROP 0 LASTPIN (-3650 4200) $PN 179
J 0
(-3640 4210);
DISPLAY 0.680851 (-3640 4210);
PAINT MONO (-3640 4210);
FORCEPROP 0 LASTPIN (-3650 3100) $PN 271
J 0
(-3640 3110);
DISPLAY 0.680851 (-3640 3110);
PAINT MONO (-3640 3110);
FORCEPROP 0 LASTPIN (-3650 3150) $PN 272
J 0
(-3640 3160);
DISPLAY 0.680851 (-3640 3160);
PAINT MONO (-3640 3160);
FORCEPROP 0 LASTPIN (-3650 4250) $PN 189
J 0
(-3640 4260);
DISPLAY 0.680851 (-3640 4260);
PAINT MONO (-3640 4260);
FORCEPROP 0 LASTPIN (-3650 4300) $PN 190
J 0
(-3640 4310);
DISPLAY 0.680851 (-3640 4310);
PAINT MONO (-3640 4310);
FORCEPROP 0 LASTPIN (-3650 3200) $PN 282
J 0
(-3640 3210);
DISPLAY 0.680851 (-3640 3210);
PAINT MONO (-3640 3210);
FORCEPROP 0 LASTPIN (-3650 3250) $PN 283
J 0
(-3640 3260);
DISPLAY 0.680851 (-3640 3260);
PAINT MONO (-3640 3260);
FORCEPROP 0 LASTPIN (-3650 4350) $PN 200
J 0
(-3640 4360);
DISPLAY 0.680851 (-3640 4360);
PAINT MONO (-3640 4360);
FORCEPROP 0 LASTPIN (-3650 4400) $PN 201
J 0
(-3640 4410);
DISPLAY 0.680851 (-3640 4410);
PAINT MONO (-3640 4410);
FORCEPROP 0 LASTPIN (-3650 3300) $PN 94
J 0
(-3640 3310);
DISPLAY 0.680851 (-3640 3310);
PAINT MONO (-3640 3310);
FORCEPROP 0 LASTPIN (-3650 3350) $PN 93
J 0
(-3640 3360);
DISPLAY 0.680851 (-3640 3360);
PAINT MONO (-3640 3360);
FORCEPROP 1 LAST MATERIAL IO
J 0
(-5000 4575);
DISPLAY 0.468085 (-5000 4575);
PAINT SKYBLUE (-5000 4575);
FORCEPROP 2 LAST VALUE SCONN288_DDR506112002KQ
J 0
(-4850 4775);
DISPLAY 0.489362 (-4850 4775);
PAINT SKYBLUE (-4850 4775);
FORCEPROP 2 LAST PART_TYPE SMLF
J 0
(-4850 4825);
DISPLAY 1.021277 (-4850 4825);
FORCEPROP 1 LAST CDS_LMAN_SYM_OUTLINE -600,1150,600,-1150
J 0
(-4400 3400);
DISPLAY 0.468085 (-4400 3400);
PAINT GREEN (-4400 3400);
DISPLAY INVISIBLE (-4400 3400);
FORCEPROP 1 LAST NEEDS_NO_SIZE TRUE
J 0
(-4400 3400);
DISPLAY 0.723404 (-4400 3400);
PAINT GREEN (-4400 3400);
DISPLAY INVISIBLE (-4400 3400);
FORCEPROP 2 LAST CDS_LIB pure_quanta
J 0
(-4400 3400);
DISPLAY INVISIBLE (-4400 3400);
FORCEPROP 1 LAST PATH I236
J 0
(-4400 3400);
DISPLAY 0.723404 (-4400 3400);
PAINT GREEN (-4400 3400);
DISPLAY INVISIBLE (-4400 3400);
FORCEPROP 1 LAST PART_NUMBER DFHST8FS479
J 0
(-5000 4650);
DISPLAY 0.468085 (-5000 4650);
PAINT SKYBLUE (-5000 4650);
DISPLAY INVISIBLE (-5000 4650);
FORCEADD GND..1
(-2825 5450);
FORCEPROP 3 LASTPIN (-2825 5500) SIG_NAME GND\g
J 0
(-2815 5510);
DISPLAY 0.659574 (-2815 5510);
PAINT MONO (-2815 5510);
DISPLAY INVISIBLE (-2815 5510);
FORCEPROP 2 LAST CDS_LIB pure_quanta_power
J 0
(-2825 5450);
DISPLAY INVISIBLE (-2825 5450);
FORCEPROP 2 LAST BOM_COST MEM
J 0
(-2800 5575);
DISPLAY 0.659574 (-2800 5575);
DISPLAY INVISIBLE (-2800 5575);
FORCEPROP 1 LAST SIZE 1B
J 0
(-2750 5400);
DISPLAY 0.723404 (-2750 5400);
PAINT GREEN (-2750 5400);
DISPLAY INVISIBLE (-2750 5400);
FORCEPROP 2 LAST ROOM MEM_EFGH_DECOUPLING_CAPS
J 0
(-2800 5525);
DISPLAY 0.659574 (-2800 5525);
PAINT RED (-2800 5525);
DISPLAY INVISIBLE (-2800 5525);
FORCEPROP 1 LAST HDL_POWER GND
J 0
(-2825 5600);
DISPLAY 0.723404 (-2825 5600);
PAINT GREEN (-2825 5600);
DISPLAY INVISIBLE (-2825 5600);
FORCEPROP 1 LAST PATH I237
J 0
(-2750 5450);
DISPLAY 0.872340 (-2750 5450);
PAINT AQUA (-2750 5450);
DISPLAY INVISIBLE (-2750 5450);
FORCEADD Q_CAP..1
R 2
(-2825 5800);
FORCEPROP 1 LAST LOCATION C534
J 2
(-2875 5900);
DISPLAY 0.489362 (-2875 5900);
PAINT SKYBLUE (-2875 5900);
FORCEPROP 0 LAST $SEC 1
J 0
(-2875 5950);
DISPLAY 0.680851 (-2875 5950);
PAINT MONO (-2875 5950);
DISPLAY INVISIBLE (-2875 5950);
FORCEPROP 0 LAST CDS_SEC 1
J 0
(-2875 5950);
DISPLAY 0.680851 (-2875 5950);
DISPLAY INVISIBLE (-2875 5950);
FORCEPROP 1 LASTPIN (-2825 5900) $PN 1
J 2
(-2835 5880);
DISPLAY 0.489362 (-2835 5880);
PAINT MONO (-2835 5880);
FORCEPROP 1 LASTPIN (-2825 5700) $PN 2
J 2
(-2835 5680);
DISPLAY 0.489362 (-2835 5680);
PAINT MONO (-2835 5680);
FORCEPROP 1 LAST VALUE 10UF
J 2
(-2875 5850);
DISPLAY 0.489362 (-2875 5850);
PAINT SKYBLUE (-2875 5850);
FORCEPROP 1 LAST PACK_TYPE C0805
J 2
(-2875 5600);
DISPLAY 0.489362 (-2875 5600);
PAINT SKYBLUE (-2875 5600);
FORCEPROP 1 LAST VOLTAGE 25V
J 2
(-2875 5800);
DISPLAY 0.489362 (-2875 5800);
PAINT SKYBLUE (-2875 5800);
FORCEPROP 1 LAST TOLERANCE 10%
J 2
(-2875 5750);
DISPLAY 0.489362 (-2875 5750);
PAINT SKYBLUE (-2875 5750);
FORCEPROP 1 LAST MATERIAL X6S
J 2
(-2875 5700);
DISPLAY 0.489362 (-2875 5700);
PAINT SKYBLUE (-2875 5700);
FORCEPROP 2 LAST CDS_LIB pure_quanta
J 0
(-2825 5800);
DISPLAY INVISIBLE (-2825 5800);
FORCEPROP 0 LAST BOM_COST MEM
J 2
(-2880 5945);
DISPLAY 0.595745 (-2880 5945);
PAINT MONO (-2880 5945);
DISPLAY INVISIBLE (-2880 5945);
FORCEPROP 2 LAST ROOM 
J 2
(-2880 5945);
DISPLAY 0.595745 (-2880 5945);
PAINT RED (-2880 5945);
DISPLAY INVISIBLE (-2880 5945);
FORCEPROP 1 LAST PATH I238
J 2
(-2875 5950);
DISPLAY 0.978723 (-2875 5950);
PAINT WHITE (-2875 5950);
DISPLAY INVISIBLE (-2875 5950);
FORCEPROP 1 LAST PART_NUMBER CH6104KEA00
J 2
(-2875 5650);
DISPLAY 0.489362 (-2875 5650);
PAINT SKYBLUE (-2875 5650);
DISPLAY INVISIBLE (-2875 5650);
FORCEADD Q_CAP..1
R 2
(-2250 5800);
FORCEPROP 1 LAST LOCATION C535
J 2
(-2300 5900);
DISPLAY 0.489362 (-2300 5900);
PAINT SKYBLUE (-2300 5900);
FORCEPROP 0 LAST $SEC 1
J 0
(-2300 5950);
DISPLAY 0.680851 (-2300 5950);
PAINT MONO (-2300 5950);
DISPLAY INVISIBLE (-2300 5950);
FORCEPROP 0 LAST CDS_SEC 1
J 0
(-2300 5950);
DISPLAY 0.680851 (-2300 5950);
DISPLAY INVISIBLE (-2300 5950);
FORCEPROP 1 LASTPIN (-2250 5900) $PN 1
J 2
(-2260 5880);
DISPLAY 0.489362 (-2260 5880);
PAINT MONO (-2260 5880);
FORCEPROP 1 LASTPIN (-2250 5700) $PN 2
J 2
(-2260 5680);
DISPLAY 0.489362 (-2260 5680);
PAINT MONO (-2260 5680);
FORCEPROP 1 LAST PACK_TYPE C0805
J 2
(-2300 5600);
DISPLAY 0.489362 (-2300 5600);
PAINT SKYBLUE (-2300 5600);
FORCEPROP 1 LAST VOLTAGE 25V
J 2
(-2300 5800);
DISPLAY 0.489362 (-2300 5800);
PAINT SKYBLUE (-2300 5800);
FORCEPROP 1 LAST VALUE 10UF
J 2
(-2300 5850);
DISPLAY 0.489362 (-2300 5850);
PAINT SKYBLUE (-2300 5850);
FORCEPROP 1 LAST TOLERANCE 10%
J 2
(-2300 5750);
DISPLAY 0.489362 (-2300 5750);
PAINT SKYBLUE (-2300 5750);
FORCEPROP 1 LAST MATERIAL X6S
J 2
(-2300 5700);
DISPLAY 0.489362 (-2300 5700);
PAINT SKYBLUE (-2300 5700);
FORCEPROP 2 LAST CDS_LIB pure_quanta
J 0
(-2250 5800);
DISPLAY INVISIBLE (-2250 5800);
FORCEPROP 0 LAST BOM_COST MEM
J 2
(-2305 5945);
DISPLAY 0.595745 (-2305 5945);
PAINT MONO (-2305 5945);
DISPLAY INVISIBLE (-2305 5945);
FORCEPROP 2 LAST ROOM 
J 2
(-2305 5945);
DISPLAY 0.595745 (-2305 5945);
PAINT RED (-2305 5945);
DISPLAY INVISIBLE (-2305 5945);
FORCEPROP 1 LAST PATH I239
J 2
(-2300 5950);
DISPLAY 0.978723 (-2300 5950);
PAINT WHITE (-2300 5950);
DISPLAY INVISIBLE (-2300 5950);
FORCEPROP 1 LAST PART_NUMBER CH6104KEA00
J 2
(-2300 5650);
DISPLAY 0.489362 (-2300 5650);
PAINT SKYBLUE (-2300 5650);
DISPLAY INVISIBLE (-2300 5650);
FORCEADD TAP..1
R 2
(-7675 3200);
FORCEPROP 3 LASTPIN (-7625 3200) SIG_NAME M_I_CPU1_SB_CB<1>
J 0
(-7615 3210);
DISPLAY 0.659574 (-7615 3210);
PAINT MONO (-7615 3210);
DISPLAY INVISIBLE (-7615 3210);
FORCEPROP 1 LASTPIN (-7625 3200) BN 1
J 2
(-7613 3208);
DISPLAY 0.489362 (-7613 3208);
PAINT GREEN (-7613 3208);
FORCEPROP 2 LAST CDS_LIB mstr_standard
J 0
(-7675 3200);
DISPLAY 0.723404 (-7675 3200);
PAINT MONO (-7675 3200);
DISPLAY INVISIBLE (-7675 3200);
FORCEPROP 1 LAST BODY_TYPE PLUMBING
J 2
(-7675 3250);
DISPLAY 0.872340 (-7675 3250);
PAINT GREEN (-7675 3250);
DISPLAY INVISIBLE (-7675 3250);
FORCEPROP 1 LAST HDL_TAP TRUE
J 2
(-8000 3075);
DISPLAY 0.872340 (-8000 3075);
DISPLAY INVISIBLE (-8000 3075);
FORCEPROP 1 LAST PATH I24
J 2
(-7673 3200);
DISPLAY 0.872340 (-7673 3200);
PAINT GREEN (-7673 3200);
DISPLAY INVISIBLE (-7673 3200);
FORCEADD UNIVERSAL_POWER..1
(-2825 6125);
FORCEPROP 3 LASTPIN (-2825 6075) SIG_NAME P12V_MEM_CPU1\g
J 0
(-2815 6085);
DISPLAY 0.659574 (-2815 6085);
PAINT MONO (-2815 6085);
DISPLAY INVISIBLE (-2815 6085);
FORCEPROP 1 LAST HDL_POWER P12V_MEM_CPU1
J 1
(-2825 6175);
DISPLAY 0.489362 (-2825 6175);
PAINT GREEN (-2825 6175);
FORCEPROP 2 LAST CDS_LIB pure_quanta_power
J 0
(-2825 6125);
DISPLAY INVISIBLE (-2825 6125);
FORCEPROP 1 LAST PATH I240
J 0
(-2775 6150);
DISPLAY 0.872340 (-2775 6150);
PAINT AQUA (-2775 6150);
DISPLAY INVISIBLE (-2775 6150);
FORCEADD OFFPAGE..1
(-8400 2575);
FORCEPROP 2 LAST $XR5 109 
J 0
(-9252 2575);
DISPLAY 0.638298 (-9252 2575);
PAINT MONO (-9252 2575);
FORCEPROP 2 LAST $XR4 108 
J 0
(-9132 2575);
DISPLAY 0.638298 (-9132 2575);
PAINT MONO (-9132 2575);
FORCEPROP 2 LAST $XR3 107 
J 0
(-9012 2575);
DISPLAY 0.638298 (-9012 2575);
PAINT MONO (-9012 2575);
FORCEPROP 2 LAST $XR2 105 
J 0
(-8892 2575);
DISPLAY 0.638298 (-8892 2575);
PAINT MONO (-8892 2575);
FORCEPROP 2 LAST $XR1 104 
J 0
(-8772 2575);
DISPLAY 0.638298 (-8772 2575);
PAINT MONO (-8772 2575);
FORCEPROP 2 LAST $XR0 159 
J 0
(-8652 2575);
DISPLAY 0.638298 (-8652 2575);
PAINT MONO (-8652 2575);
FORCEPROP 2 LAST CDS_LIB mstr_standard
J 0
(-8400 2575);
DISPLAY 0.808511 (-8400 2575);
DISPLAY INVISIBLE (-8400 2575);
FORCEPROP 1 LAST OFFPAGE TRUE
J 0
(-8075 2450);
DISPLAY 0.872340 (-8075 2450);
PAINT GREEN (-8075 2450);
DISPLAY INVISIBLE (-8075 2450);
FORCEPROP 1 LAST COMMENT_BODY TRUE
J 0
(-8275 2475);
DISPLAY 0.872340 (-8275 2475);
PAINT GREEN (-8275 2475);
DISPLAY INVISIBLE (-8275 2475);
FORCEPROP 2 LAST PATH I241
J 0
(-8675 2625);
DISPLAY 0.680851 (-8675 2625);
DISPLAY INVISIBLE (-8675 2625);
FORCEADD Q_RES..1
(-7725 2575);
FORCEPROP 1 LAST LOCATION R1588
J 0
(-7775 2600);
DISPLAY 0.510638 (-7775 2600);
PAINT SKYBLUE (-7775 2600);
FORCEPROP 0 LAST $SEC 1
J 0
(-7775 2675);
DISPLAY 0.680851 (-7775 2675);
PAINT MONO (-7775 2675);
DISPLAY INVISIBLE (-7775 2675);
FORCEPROP 0 LAST CDS_SEC 1
J 0
(-7775 2675);
DISPLAY 0.680851 (-7775 2675);
DISPLAY INVISIBLE (-7775 2675);
FORCEPROP 1 LASTPIN (-7825 2575) $PN 1
J 0
(-7813 2587);
DISPLAY 0.787234 (-7813 2587);
PAINT MONO (-7813 2587);
FORCEPROP 1 LASTPIN (-7625 2575) $PN 2
J 0
(-7663 2587);
DISPLAY 0.787234 (-7663 2587);
PAINT MONO (-7663 2587);
FORCEPROP 1 LAST VALUE 49.9
J 2
(-7575 2625);
DISPLAY 0.510638 (-7575 2625);
PAINT SKYBLUE (-7575 2625);
FORCEPROP 2 LAST CDS_LIB pure_quanta
J 0
(-7725 2575);
DISPLAY INVISIBLE (-7725 2575);
FORCEPROP 1 LAST TOLERANCE 1%
J 0
(-7725 2475);
DISPLAY 0.978723 (-7725 2475);
DISPLAY INVISIBLE (-7725 2475);
FORCEPROP 1 LAST WATTAGE 1/16W
J 2
(-7750 2425);
DISPLAY 0.978723 (-7750 2425);
DISPLAY INVISIBLE (-7750 2425);
FORCEPROP 1 LAST PACK_TYPE 0402LF
J 0
(-7475 2425);
DISPLAY 0.978723 (-7475 2425);
DISPLAY INVISIBLE (-7475 2425);
FORCEPROP 1 LAST MATERIAL CHIP
J 0
(-7725 2425);
DISPLAY 0.978723 (-7725 2425);
DISPLAY INVISIBLE (-7725 2425);
FORCEPROP 1 LAST PATH I242
J 0
(-7775 2725);
DISPLAY 0.978723 (-7775 2725);
PAINT WHITE (-7775 2725);
DISPLAY INVISIBLE (-7775 2725);
FORCEPROP 1 LAST PART_NUMBER CS04992FB07
J 0
(-7775 2675);
DISPLAY 0.978723 (-7775 2675);
DISPLAY INVISIBLE (-7775 2675);
FORCEADD Q_RES..1
(-8100 2800);
FORCEPROP 1 LAST LOCATION R1708
J 0
(-8275 2800);
DISPLAY 0.638298 (-8275 2800);
FORCEPROP 0 LAST $SEC 1
J 0
(-8275 2850);
DISPLAY 0.680851 (-8275 2850);
PAINT MONO (-8275 2850);
DISPLAY INVISIBLE (-8275 2850);
FORCEPROP 0 LAST CDS_SEC 1
J 0
(-8275 2850);
DISPLAY 0.680851 (-8275 2850);
DISPLAY INVISIBLE (-8275 2850);
FORCEPROP 1 LASTPIN (-8200 2800) $PN 1
J 0
(-8188 2812);
DISPLAY 0.787234 (-8188 2812);
PAINT MONO (-8188 2812);
FORCEPROP 1 LASTPIN (-8000 2800) $PN 2
J 0
(-8038 2812);
DISPLAY 0.787234 (-8038 2812);
PAINT MONO (-8038 2812);
FORCEPROP 1 LAST MATERIAL CHIP
J 0
(-8200 2775);
DISPLAY 0.404255 (-8200 2775);
FORCEPROP 1 LAST PACK_TYPE 0402LF
J 0
(-8050 2775);
DISPLAY 0.404255 (-8050 2775);
FORCEPROP 1 LAST VALUE 10
J 2
(-7950 2800);
DISPLAY 0.404255 (-7950 2800);
FORCEPROP 1 LAST TOLERANCE 1%
J 0
(-8100 2700);
DISPLAY 0.978723 (-8100 2700);
DISPLAY INVISIBLE (-8100 2700);
FORCEPROP 1 LAST WATTAGE 1/16W
J 2
(-8125 2650);
DISPLAY 0.978723 (-8125 2650);
DISPLAY INVISIBLE (-8125 2650);
FORCEPROP 2 LAST CDS_LIB pure_quanta
J 0
(-8100 2800);
DISPLAY INVISIBLE (-8100 2800);
FORCEPROP 1 LAST PATH I243
J 0
(-8150 2950);
DISPLAY 0.978723 (-8150 2950);
PAINT WHITE (-8150 2950);
DISPLAY INVISIBLE (-8150 2950);
FORCEPROP 1 LAST PART_NUMBER CS01002FB07
J 0
(-8150 2900);
DISPLAY 0.978723 (-8150 2900);
DISPLAY INVISIBLE (-8150 2900);
FORCEADD OFFPAGE..6
(-8750 2700);
FORCEPROP 2 LAST $XR5 159 
J 0
(-9270 2664);
DISPLAY 0.638298 (-9270 2664);
PAINT MONO (-9270 2664);
FORCEPROP 2 LAST $XR4 109 
J 0
(-9150 2664);
DISPLAY 0.638298 (-9150 2664);
PAINT MONO (-9150 2664);
FORCEPROP 2 LAST $XR3 108 
J 0
(-9030 2664);
DISPLAY 0.638298 (-9030 2664);
PAINT MONO (-9030 2664);
FORCEPROP 2 LAST $XR2 107 
J 0
(-9270 2700);
DISPLAY 0.638298 (-9270 2700);
PAINT MONO (-9270 2700);
FORCEPROP 2 LAST $XR1 105 
J 0
(-9150 2700);
DISPLAY 0.638298 (-9150 2700);
PAINT MONO (-9150 2700);
FORCEPROP 2 LAST $XR0 104 
J 0
(-9030 2700);
DISPLAY 0.638298 (-9030 2700);
PAINT MONO (-9030 2700);
FORCEPROP 2 LAST CDS_LIB mstr_standard
J 0
(-8750 2700);
DISPLAY 0.808511 (-8750 2700);
DISPLAY INVISIBLE (-8750 2700);
FORCEPROP 1 LAST OFFPAGE TRUE
J 0
(-8425 2575);
DISPLAY 0.872340 (-8425 2575);
PAINT GREEN (-8425 2575);
DISPLAY INVISIBLE (-8425 2575);
FORCEPROP 1 LAST COMMENT_BODY TRUE
J 0
(-8650 2625);
DISPLAY 0.872340 (-8650 2625);
PAINT GREEN (-8650 2625);
DISPLAY INVISIBLE (-8650 2625);
FORCEPROP 2 LAST PATH I244
J 0
(-9050 2750);
DISPLAY 0.680851 (-9050 2750);
DISPLAY INVISIBLE (-9050 2750);
FORCEADD TAP..1
R 2
(-7675 3250);
FORCEPROP 3 LASTPIN (-7625 3250) SIG_NAME M_I_CPU1_SB_CB<2>
J 0
(-7615 3260);
DISPLAY 0.659574 (-7615 3260);
PAINT MONO (-7615 3260);
DISPLAY INVISIBLE (-7615 3260);
FORCEPROP 1 LASTPIN (-7625 3250) BN 2
J 2
(-7613 3258);
DISPLAY 0.489362 (-7613 3258);
PAINT GREEN (-7613 3258);
FORCEPROP 2 LAST CDS_LIB mstr_standard
J 0
(-7675 3250);
DISPLAY 0.723404 (-7675 3250);
PAINT MONO (-7675 3250);
DISPLAY INVISIBLE (-7675 3250);
FORCEPROP 1 LAST BODY_TYPE PLUMBING
J 2
(-7675 3300);
DISPLAY 0.872340 (-7675 3300);
PAINT GREEN (-7675 3300);
DISPLAY INVISIBLE (-7675 3300);
FORCEPROP 1 LAST HDL_TAP TRUE
J 2
(-8000 3125);
DISPLAY 0.872340 (-8000 3125);
DISPLAY INVISIBLE (-8000 3125);
FORCEPROP 1 LAST PATH I25
J 2
(-7673 3250);
DISPLAY 0.872340 (-7673 3250);
PAINT GREEN (-7673 3250);
DISPLAY INVISIBLE (-7673 3250);
FORCEADD TAP..1
R 2
(-7675 3300);
FORCEPROP 3 LASTPIN (-7625 3300) SIG_NAME M_I_CPU1_SB_CB<3>
J 0
(-7615 3310);
DISPLAY 0.659574 (-7615 3310);
PAINT MONO (-7615 3310);
DISPLAY INVISIBLE (-7615 3310);
FORCEPROP 1 LASTPIN (-7625 3300) BN 3
J 2
(-7613 3308);
DISPLAY 0.489362 (-7613 3308);
PAINT GREEN (-7613 3308);
FORCEPROP 2 LAST CDS_LIB mstr_standard
J 0
(-7675 3300);
DISPLAY 0.723404 (-7675 3300);
PAINT MONO (-7675 3300);
DISPLAY INVISIBLE (-7675 3300);
FORCEPROP 1 LAST BODY_TYPE PLUMBING
J 2
(-7675 3350);
DISPLAY 0.872340 (-7675 3350);
PAINT GREEN (-7675 3350);
DISPLAY INVISIBLE (-7675 3350);
FORCEPROP 1 LAST HDL_TAP TRUE
J 2
(-8000 3175);
DISPLAY 0.872340 (-8000 3175);
DISPLAY INVISIBLE (-8000 3175);
FORCEPROP 1 LAST PATH I26
J 2
(-7673 3300);
DISPLAY 0.872340 (-7673 3300);
PAINT GREEN (-7673 3300);
DISPLAY INVISIBLE (-7673 3300);
FORCEADD TAP..1
R 2
(-7675 3350);
FORCEPROP 3 LASTPIN (-7625 3350) SIG_NAME M_I_CPU1_SB_CB<4>
J 0
(-7615 3360);
DISPLAY 0.659574 (-7615 3360);
PAINT MONO (-7615 3360);
DISPLAY INVISIBLE (-7615 3360);
FORCEPROP 1 LASTPIN (-7625 3350) BN 4
J 2
(-7613 3358);
DISPLAY 0.489362 (-7613 3358);
PAINT GREEN (-7613 3358);
FORCEPROP 2 LAST CDS_LIB mstr_standard
J 0
(-7675 3350);
DISPLAY 0.723404 (-7675 3350);
PAINT MONO (-7675 3350);
DISPLAY INVISIBLE (-7675 3350);
FORCEPROP 1 LAST BODY_TYPE PLUMBING
J 2
(-7675 3400);
DISPLAY 0.872340 (-7675 3400);
PAINT GREEN (-7675 3400);
DISPLAY INVISIBLE (-7675 3400);
FORCEPROP 1 LAST HDL_TAP TRUE
J 2
(-8000 3225);
DISPLAY 0.872340 (-8000 3225);
DISPLAY INVISIBLE (-8000 3225);
FORCEPROP 1 LAST PATH I27
J 2
(-7673 3350);
DISPLAY 0.872340 (-7673 3350);
PAINT GREEN (-7673 3350);
DISPLAY INVISIBLE (-7673 3350);
FORCEADD TAP..1
R 2
(-7675 3400);
FORCEPROP 3 LASTPIN (-7625 3400) SIG_NAME M_I_CPU1_SB_CB<5>
J 0
(-7615 3410);
DISPLAY 0.659574 (-7615 3410);
PAINT MONO (-7615 3410);
DISPLAY INVISIBLE (-7615 3410);
FORCEPROP 1 LASTPIN (-7625 3400) BN 5
J 2
(-7613 3408);
DISPLAY 0.489362 (-7613 3408);
PAINT GREEN (-7613 3408);
FORCEPROP 2 LAST CDS_LIB mstr_standard
J 0
(-7675 3400);
DISPLAY 0.723404 (-7675 3400);
PAINT MONO (-7675 3400);
DISPLAY INVISIBLE (-7675 3400);
FORCEPROP 1 LAST BODY_TYPE PLUMBING
J 2
(-7675 3450);
DISPLAY 0.872340 (-7675 3450);
PAINT GREEN (-7675 3450);
DISPLAY INVISIBLE (-7675 3450);
FORCEPROP 1 LAST HDL_TAP TRUE
J 2
(-8000 3275);
DISPLAY 0.872340 (-8000 3275);
DISPLAY INVISIBLE (-8000 3275);
FORCEPROP 1 LAST PATH I28
J 2
(-7673 3400);
DISPLAY 0.872340 (-7673 3400);
PAINT GREEN (-7673 3400);
DISPLAY INVISIBLE (-7673 3400);
FORCEADD TAP..1
R 2
(-7675 3450);
FORCEPROP 3 LASTPIN (-7625 3450) SIG_NAME M_I_CPU1_SB_CB<6>
J 0
(-7615 3460);
DISPLAY 0.659574 (-7615 3460);
PAINT MONO (-7615 3460);
DISPLAY INVISIBLE (-7615 3460);
FORCEPROP 1 LASTPIN (-7625 3450) BN 6
J 2
(-7613 3458);
DISPLAY 0.489362 (-7613 3458);
PAINT GREEN (-7613 3458);
FORCEPROP 2 LAST CDS_LIB mstr_standard
J 0
(-7675 3450);
DISPLAY 0.723404 (-7675 3450);
PAINT MONO (-7675 3450);
DISPLAY INVISIBLE (-7675 3450);
FORCEPROP 1 LAST BODY_TYPE PLUMBING
J 2
(-7675 3500);
DISPLAY 0.872340 (-7675 3500);
PAINT GREEN (-7675 3500);
DISPLAY INVISIBLE (-7675 3500);
FORCEPROP 1 LAST HDL_TAP TRUE
J 2
(-8000 3325);
DISPLAY 0.872340 (-8000 3325);
DISPLAY INVISIBLE (-8000 3325);
FORCEPROP 1 LAST PATH I29
J 2
(-7673 3450);
DISPLAY 0.872340 (-7673 3450);
PAINT GREEN (-7673 3450);
DISPLAY INVISIBLE (-7673 3450);
FORCEADD TAP..1
R 2
(-7675 3500);
FORCEPROP 3 LASTPIN (-7625 3500) SIG_NAME M_I_CPU1_SB_CB<7>
J 0
(-7615 3510);
DISPLAY 0.659574 (-7615 3510);
PAINT MONO (-7615 3510);
DISPLAY INVISIBLE (-7615 3510);
FORCEPROP 1 LASTPIN (-7625 3500) BN 7
J 2
(-7613 3508);
DISPLAY 0.489362 (-7613 3508);
PAINT GREEN (-7613 3508);
FORCEPROP 2 LAST CDS_LIB mstr_standard
J 0
(-7675 3500);
DISPLAY 0.723404 (-7675 3500);
PAINT MONO (-7675 3500);
DISPLAY INVISIBLE (-7675 3500);
FORCEPROP 1 LAST BODY_TYPE PLUMBING
J 2
(-7675 3550);
DISPLAY 0.872340 (-7675 3550);
PAINT GREEN (-7675 3550);
DISPLAY INVISIBLE (-7675 3550);
FORCEPROP 1 LAST HDL_TAP TRUE
J 2
(-8000 3375);
DISPLAY 0.872340 (-8000 3375);
DISPLAY INVISIBLE (-8000 3375);
FORCEPROP 1 LAST PATH I30
J 2
(-7673 3500);
DISPLAY 0.872340 (-7673 3500);
PAINT GREEN (-7673 3500);
DISPLAY INVISIBLE (-7673 3500);
FORCEADD TAP..1
R 2
(-7675 3600);
FORCEPROP 3 LASTPIN (-7625 3600) SIG_NAME M_I_CPU1_SA_CB<0>
J 0
(-7615 3610);
DISPLAY 0.659574 (-7615 3610);
PAINT MONO (-7615 3610);
DISPLAY INVISIBLE (-7615 3610);
FORCEPROP 1 LASTPIN (-7625 3600) BN 0
J 2
(-7613 3608);
DISPLAY 0.489362 (-7613 3608);
PAINT GREEN (-7613 3608);
FORCEPROP 2 LAST CDS_LIB mstr_standard
J 0
(-7675 3600);
DISPLAY 0.723404 (-7675 3600);
PAINT MONO (-7675 3600);
DISPLAY INVISIBLE (-7675 3600);
FORCEPROP 1 LAST BODY_TYPE PLUMBING
J 2
(-7675 3650);
DISPLAY 0.872340 (-7675 3650);
PAINT GREEN (-7675 3650);
DISPLAY INVISIBLE (-7675 3650);
FORCEPROP 1 LAST HDL_TAP TRUE
J 2
(-8000 3475);
DISPLAY 0.872340 (-8000 3475);
DISPLAY INVISIBLE (-8000 3475);
FORCEPROP 1 LAST PATH I31
J 2
(-7673 3600);
DISPLAY 0.872340 (-7673 3600);
PAINT GREEN (-7673 3600);
DISPLAY INVISIBLE (-7673 3600);
FORCEADD TAP..1
R 2
(-7675 3650);
FORCEPROP 3 LASTPIN (-7625 3650) SIG_NAME M_I_CPU1_SA_CB<1>
J 0
(-7615 3660);
DISPLAY 0.659574 (-7615 3660);
PAINT MONO (-7615 3660);
DISPLAY INVISIBLE (-7615 3660);
FORCEPROP 1 LASTPIN (-7625 3650) BN 1
J 2
(-7613 3658);
DISPLAY 0.489362 (-7613 3658);
PAINT GREEN (-7613 3658);
FORCEPROP 2 LAST CDS_LIB mstr_standard
J 0
(-7675 3650);
DISPLAY 0.723404 (-7675 3650);
PAINT MONO (-7675 3650);
DISPLAY INVISIBLE (-7675 3650);
FORCEPROP 1 LAST BODY_TYPE PLUMBING
J 2
(-7675 3700);
DISPLAY 0.872340 (-7675 3700);
PAINT GREEN (-7675 3700);
DISPLAY INVISIBLE (-7675 3700);
FORCEPROP 1 LAST HDL_TAP TRUE
J 2
(-8000 3525);
DISPLAY 0.872340 (-8000 3525);
DISPLAY INVISIBLE (-8000 3525);
FORCEPROP 1 LAST PATH I32
J 2
(-7673 3650);
DISPLAY 0.872340 (-7673 3650);
PAINT GREEN (-7673 3650);
DISPLAY INVISIBLE (-7673 3650);
FORCEADD TAP..1
R 2
(-7675 3750);
FORCEPROP 3 LASTPIN (-7625 3750) SIG_NAME M_I_CPU1_SA_CB<3>
J 0
(-7615 3760);
DISPLAY 0.659574 (-7615 3760);
PAINT MONO (-7615 3760);
DISPLAY INVISIBLE (-7615 3760);
FORCEPROP 1 LASTPIN (-7625 3750) BN 3
J 2
(-7613 3758);
DISPLAY 0.489362 (-7613 3758);
PAINT GREEN (-7613 3758);
FORCEPROP 2 LAST CDS_LIB mstr_standard
J 0
(-7675 3750);
DISPLAY 0.723404 (-7675 3750);
PAINT MONO (-7675 3750);
DISPLAY INVISIBLE (-7675 3750);
FORCEPROP 1 LAST BODY_TYPE PLUMBING
J 2
(-7675 3800);
DISPLAY 0.872340 (-7675 3800);
PAINT GREEN (-7675 3800);
DISPLAY INVISIBLE (-7675 3800);
FORCEPROP 1 LAST HDL_TAP TRUE
J 2
(-8000 3625);
DISPLAY 0.872340 (-8000 3625);
DISPLAY INVISIBLE (-8000 3625);
FORCEPROP 1 LAST PATH I33
J 2
(-7673 3750);
DISPLAY 0.872340 (-7673 3750);
PAINT GREEN (-7673 3750);
DISPLAY INVISIBLE (-7673 3750);
FORCEADD TAP..1
R 2
(-7675 3700);
FORCEPROP 3 LASTPIN (-7625 3700) SIG_NAME M_I_CPU1_SA_CB<2>
J 0
(-7615 3710);
DISPLAY 0.659574 (-7615 3710);
PAINT MONO (-7615 3710);
DISPLAY INVISIBLE (-7615 3710);
FORCEPROP 1 LASTPIN (-7625 3700) BN 2
J 2
(-7613 3708);
DISPLAY 0.489362 (-7613 3708);
PAINT GREEN (-7613 3708);
FORCEPROP 2 LAST CDS_LIB mstr_standard
J 0
(-7675 3700);
DISPLAY 0.723404 (-7675 3700);
PAINT MONO (-7675 3700);
DISPLAY INVISIBLE (-7675 3700);
FORCEPROP 1 LAST BODY_TYPE PLUMBING
J 2
(-7675 3750);
DISPLAY 0.872340 (-7675 3750);
PAINT GREEN (-7675 3750);
DISPLAY INVISIBLE (-7675 3750);
FORCEPROP 1 LAST HDL_TAP TRUE
J 2
(-8000 3575);
DISPLAY 0.872340 (-8000 3575);
DISPLAY INVISIBLE (-8000 3575);
FORCEPROP 1 LAST PATH I34
J 2
(-7673 3700);
DISPLAY 0.872340 (-7673 3700);
PAINT GREEN (-7673 3700);
DISPLAY INVISIBLE (-7673 3700);
FORCEADD TAP..1
(-5975 2150);
FORCEPROP 3 LASTPIN (-6025 2150) SIG_NAME M_I_CPU1_SB_DQ<0>
J 0
(-6015 2160);
DISPLAY 0.659574 (-6015 2160);
PAINT MONO (-6015 2160);
DISPLAY INVISIBLE (-6015 2160);
FORCEPROP 1 LASTPIN (-6025 2150) BN 0
J 0
(-6037 2158);
DISPLAY 0.489362 (-6037 2158);
PAINT GREEN (-6037 2158);
FORCEPROP 2 LAST CDS_LIB mstr_standard
J 0
(-5975 2150);
DISPLAY 0.723404 (-5975 2150);
PAINT MONO (-5975 2150);
DISPLAY INVISIBLE (-5975 2150);
FORCEPROP 1 LAST BODY_TYPE PLUMBING
J 0
(-5975 2200);
DISPLAY 0.872340 (-5975 2200);
PAINT GREEN (-5975 2200);
DISPLAY INVISIBLE (-5975 2200);
FORCEPROP 1 LAST HDL_TAP TRUE
J 0
(-5650 2025);
DISPLAY 0.872340 (-5650 2025);
DISPLAY INVISIBLE (-5650 2025);
FORCEPROP 1 LAST PATH I35
J 0
(-5977 2150);
DISPLAY 0.872340 (-5977 2150);
PAINT GREEN (-5977 2150);
DISPLAY INVISIBLE (-5977 2150);
FORCEADD TAP..1
(-5975 2250);
FORCEPROP 3 LASTPIN (-6025 2250) SIG_NAME M_I_CPU1_SB_DQ<2>
J 0
(-6015 2260);
DISPLAY 0.659574 (-6015 2260);
PAINT MONO (-6015 2260);
DISPLAY INVISIBLE (-6015 2260);
FORCEPROP 1 LASTPIN (-6025 2250) BN 2
J 0
(-6037 2258);
DISPLAY 0.489362 (-6037 2258);
PAINT GREEN (-6037 2258);
FORCEPROP 2 LAST CDS_LIB mstr_standard
J 0
(-5975 2250);
DISPLAY 0.723404 (-5975 2250);
PAINT MONO (-5975 2250);
DISPLAY INVISIBLE (-5975 2250);
FORCEPROP 1 LAST BODY_TYPE PLUMBING
J 0
(-5975 2300);
DISPLAY 0.872340 (-5975 2300);
PAINT GREEN (-5975 2300);
DISPLAY INVISIBLE (-5975 2300);
FORCEPROP 1 LAST HDL_TAP TRUE
J 0
(-5650 2125);
DISPLAY 0.872340 (-5650 2125);
DISPLAY INVISIBLE (-5650 2125);
FORCEPROP 1 LAST PATH I36
J 0
(-5977 2250);
DISPLAY 0.872340 (-5977 2250);
PAINT GREEN (-5977 2250);
DISPLAY INVISIBLE (-5977 2250);
FORCEADD TAP..1
(-5975 2200);
FORCEPROP 3 LASTPIN (-6025 2200) SIG_NAME M_I_CPU1_SB_DQ<1>
J 0
(-6015 2210);
DISPLAY 0.659574 (-6015 2210);
PAINT MONO (-6015 2210);
DISPLAY INVISIBLE (-6015 2210);
FORCEPROP 1 LASTPIN (-6025 2200) BN 1
J 0
(-6037 2208);
DISPLAY 0.489362 (-6037 2208);
PAINT GREEN (-6037 2208);
FORCEPROP 2 LAST CDS_LIB mstr_standard
J 0
(-5975 2200);
DISPLAY 0.723404 (-5975 2200);
PAINT MONO (-5975 2200);
DISPLAY INVISIBLE (-5975 2200);
FORCEPROP 1 LAST BODY_TYPE PLUMBING
J 0
(-5975 2250);
DISPLAY 0.872340 (-5975 2250);
PAINT GREEN (-5975 2250);
DISPLAY INVISIBLE (-5975 2250);
FORCEPROP 1 LAST HDL_TAP TRUE
J 0
(-5650 2075);
DISPLAY 0.872340 (-5650 2075);
DISPLAY INVISIBLE (-5650 2075);
FORCEPROP 1 LAST PATH I37
J 0
(-5977 2200);
DISPLAY 0.872340 (-5977 2200);
PAINT GREEN (-5977 2200);
DISPLAY INVISIBLE (-5977 2200);
FORCEADD TAP..1
(-5975 2350);
FORCEPROP 3 LASTPIN (-6025 2350) SIG_NAME M_I_CPU1_SB_DQ<4>
J 0
(-6015 2360);
DISPLAY 0.659574 (-6015 2360);
PAINT MONO (-6015 2360);
DISPLAY INVISIBLE (-6015 2360);
FORCEPROP 1 LASTPIN (-6025 2350) BN 4
J 0
(-6037 2358);
DISPLAY 0.489362 (-6037 2358);
PAINT GREEN (-6037 2358);
FORCEPROP 2 LAST CDS_LIB mstr_standard
J 0
(-5975 2350);
DISPLAY 0.723404 (-5975 2350);
PAINT MONO (-5975 2350);
DISPLAY INVISIBLE (-5975 2350);
FORCEPROP 1 LAST BODY_TYPE PLUMBING
J 0
(-5975 2400);
DISPLAY 0.872340 (-5975 2400);
PAINT GREEN (-5975 2400);
DISPLAY INVISIBLE (-5975 2400);
FORCEPROP 1 LAST HDL_TAP TRUE
J 0
(-5650 2225);
DISPLAY 0.872340 (-5650 2225);
DISPLAY INVISIBLE (-5650 2225);
FORCEPROP 1 LAST PATH I38
J 0
(-5977 2350);
DISPLAY 0.872340 (-5977 2350);
PAINT GREEN (-5977 2350);
DISPLAY INVISIBLE (-5977 2350);
FORCEADD TAP..1
(-5975 2300);
FORCEPROP 3 LASTPIN (-6025 2300) SIG_NAME M_I_CPU1_SB_DQ<3>
J 0
(-6015 2310);
DISPLAY 0.659574 (-6015 2310);
PAINT MONO (-6015 2310);
DISPLAY INVISIBLE (-6015 2310);
FORCEPROP 1 LASTPIN (-6025 2300) BN 3
J 0
(-6037 2308);
DISPLAY 0.489362 (-6037 2308);
PAINT GREEN (-6037 2308);
FORCEPROP 2 LAST CDS_LIB mstr_standard
J 0
(-5975 2300);
DISPLAY 0.723404 (-5975 2300);
PAINT MONO (-5975 2300);
DISPLAY INVISIBLE (-5975 2300);
FORCEPROP 1 LAST BODY_TYPE PLUMBING
J 0
(-5975 2350);
DISPLAY 0.872340 (-5975 2350);
PAINT GREEN (-5975 2350);
DISPLAY INVISIBLE (-5975 2350);
FORCEPROP 1 LAST HDL_TAP TRUE
J 0
(-5650 2175);
DISPLAY 0.872340 (-5650 2175);
DISPLAY INVISIBLE (-5650 2175);
FORCEPROP 1 LAST PATH I39
J 0
(-5977 2300);
DISPLAY 0.872340 (-5977 2300);
PAINT GREEN (-5977 2300);
DISPLAY INVISIBLE (-5977 2300);
FORCEADD TAP..1
(-5975 2400);
FORCEPROP 3 LASTPIN (-6025 2400) SIG_NAME M_I_CPU1_SB_DQ<5>
J 0
(-6015 2410);
DISPLAY 0.659574 (-6015 2410);
PAINT MONO (-6015 2410);
DISPLAY INVISIBLE (-6015 2410);
FORCEPROP 1 LASTPIN (-6025 2400) BN 5
J 0
(-6037 2408);
DISPLAY 0.489362 (-6037 2408);
PAINT GREEN (-6037 2408);
FORCEPROP 2 LAST CDS_LIB mstr_standard
J 0
(-5975 2400);
DISPLAY 0.723404 (-5975 2400);
PAINT MONO (-5975 2400);
DISPLAY INVISIBLE (-5975 2400);
FORCEPROP 1 LAST BODY_TYPE PLUMBING
J 0
(-5975 2450);
DISPLAY 0.872340 (-5975 2450);
PAINT GREEN (-5975 2450);
DISPLAY INVISIBLE (-5975 2450);
FORCEPROP 1 LAST HDL_TAP TRUE
J 0
(-5650 2275);
DISPLAY 0.872340 (-5650 2275);
DISPLAY INVISIBLE (-5650 2275);
FORCEPROP 1 LAST PATH I40
J 0
(-5977 2400);
DISPLAY 0.872340 (-5977 2400);
PAINT GREEN (-5977 2400);
DISPLAY INVISIBLE (-5977 2400);
FORCEADD TAP..1
(-5975 2450);
FORCEPROP 3 LASTPIN (-6025 2450) SIG_NAME M_I_CPU1_SB_DQ<6>
J 0
(-6015 2460);
DISPLAY 0.659574 (-6015 2460);
PAINT MONO (-6015 2460);
DISPLAY INVISIBLE (-6015 2460);
FORCEPROP 1 LASTPIN (-6025 2450) BN 6
J 0
(-6037 2458);
DISPLAY 0.489362 (-6037 2458);
PAINT GREEN (-6037 2458);
FORCEPROP 2 LAST CDS_LIB mstr_standard
J 0
(-5975 2450);
DISPLAY 0.723404 (-5975 2450);
PAINT MONO (-5975 2450);
DISPLAY INVISIBLE (-5975 2450);
FORCEPROP 1 LAST BODY_TYPE PLUMBING
J 0
(-5975 2500);
DISPLAY 0.872340 (-5975 2500);
PAINT GREEN (-5975 2500);
DISPLAY INVISIBLE (-5975 2500);
FORCEPROP 1 LAST HDL_TAP TRUE
J 0
(-5650 2325);
DISPLAY 0.872340 (-5650 2325);
DISPLAY INVISIBLE (-5650 2325);
FORCEPROP 1 LAST PATH I41
J 0
(-5977 2450);
DISPLAY 0.872340 (-5977 2450);
PAINT GREEN (-5977 2450);
DISPLAY INVISIBLE (-5977 2450);
FORCEADD TAP..1
(-5975 2500);
FORCEPROP 3 LASTPIN (-6025 2500) SIG_NAME M_I_CPU1_SB_DQ<7>
J 0
(-6015 2510);
DISPLAY 0.659574 (-6015 2510);
PAINT MONO (-6015 2510);
DISPLAY INVISIBLE (-6015 2510);
FORCEPROP 1 LASTPIN (-6025 2500) BN 7
J 0
(-6037 2508);
DISPLAY 0.489362 (-6037 2508);
PAINT GREEN (-6037 2508);
FORCEPROP 2 LAST CDS_LIB mstr_standard
J 0
(-5975 2500);
DISPLAY 0.723404 (-5975 2500);
PAINT MONO (-5975 2500);
DISPLAY INVISIBLE (-5975 2500);
FORCEPROP 1 LAST BODY_TYPE PLUMBING
J 0
(-5975 2550);
DISPLAY 0.872340 (-5975 2550);
PAINT GREEN (-5975 2550);
DISPLAY INVISIBLE (-5975 2550);
FORCEPROP 1 LAST HDL_TAP TRUE
J 0
(-5650 2375);
DISPLAY 0.872340 (-5650 2375);
DISPLAY INVISIBLE (-5650 2375);
FORCEPROP 1 LAST PATH I42
J 0
(-5977 2500);
DISPLAY 0.872340 (-5977 2500);
PAINT GREEN (-5977 2500);
DISPLAY INVISIBLE (-5977 2500);
FORCEADD TAP..1
(-5975 2600);
FORCEPROP 3 LASTPIN (-6025 2600) SIG_NAME M_I_CPU1_SB_DQ<9>
J 0
(-6015 2610);
DISPLAY 0.659574 (-6015 2610);
PAINT MONO (-6015 2610);
DISPLAY INVISIBLE (-6015 2610);
FORCEPROP 1 LASTPIN (-6025 2600) BN 9
J 0
(-6037 2608);
DISPLAY 0.489362 (-6037 2608);
PAINT GREEN (-6037 2608);
FORCEPROP 2 LAST CDS_LIB mstr_standard
J 0
(-5975 2600);
DISPLAY 0.723404 (-5975 2600);
PAINT MONO (-5975 2600);
DISPLAY INVISIBLE (-5975 2600);
FORCEPROP 1 LAST BODY_TYPE PLUMBING
J 0
(-5975 2650);
DISPLAY 0.872340 (-5975 2650);
PAINT GREEN (-5975 2650);
DISPLAY INVISIBLE (-5975 2650);
FORCEPROP 1 LAST HDL_TAP TRUE
J 0
(-5650 2475);
DISPLAY 0.872340 (-5650 2475);
DISPLAY INVISIBLE (-5650 2475);
FORCEPROP 1 LAST PATH I43
J 0
(-5977 2600);
DISPLAY 0.872340 (-5977 2600);
PAINT GREEN (-5977 2600);
DISPLAY INVISIBLE (-5977 2600);
FORCEADD TAP..1
(-5975 2550);
FORCEPROP 3 LASTPIN (-6025 2550) SIG_NAME M_I_CPU1_SB_DQ<8>
J 0
(-6015 2560);
DISPLAY 0.659574 (-6015 2560);
PAINT MONO (-6015 2560);
DISPLAY INVISIBLE (-6015 2560);
FORCEPROP 1 LASTPIN (-6025 2550) BN 8
J 0
(-6037 2558);
DISPLAY 0.489362 (-6037 2558);
PAINT GREEN (-6037 2558);
FORCEPROP 2 LAST CDS_LIB mstr_standard
J 0
(-5975 2550);
DISPLAY 0.723404 (-5975 2550);
PAINT MONO (-5975 2550);
DISPLAY INVISIBLE (-5975 2550);
FORCEPROP 1 LAST BODY_TYPE PLUMBING
J 0
(-5975 2600);
DISPLAY 0.872340 (-5975 2600);
PAINT GREEN (-5975 2600);
DISPLAY INVISIBLE (-5975 2600);
FORCEPROP 1 LAST HDL_TAP TRUE
J 0
(-5650 2425);
DISPLAY 0.872340 (-5650 2425);
DISPLAY INVISIBLE (-5650 2425);
FORCEPROP 1 LAST PATH I44
J 0
(-5977 2550);
DISPLAY 0.872340 (-5977 2550);
PAINT GREEN (-5977 2550);
DISPLAY INVISIBLE (-5977 2550);
FORCEADD TAP..1
(-5975 2650);
FORCEPROP 3 LASTPIN (-6025 2650) SIG_NAME M_I_CPU1_SB_DQ<10>
J 0
(-6015 2660);
DISPLAY 0.659574 (-6015 2660);
PAINT MONO (-6015 2660);
DISPLAY INVISIBLE (-6015 2660);
FORCEPROP 1 LASTPIN (-6025 2650) BN 10
J 0
(-6037 2658);
DISPLAY 0.489362 (-6037 2658);
PAINT GREEN (-6037 2658);
FORCEPROP 2 LAST CDS_LIB mstr_standard
J 0
(-5975 2650);
DISPLAY 0.723404 (-5975 2650);
PAINT MONO (-5975 2650);
DISPLAY INVISIBLE (-5975 2650);
FORCEPROP 1 LAST BODY_TYPE PLUMBING
J 0
(-5975 2700);
DISPLAY 0.872340 (-5975 2700);
PAINT GREEN (-5975 2700);
DISPLAY INVISIBLE (-5975 2700);
FORCEPROP 1 LAST HDL_TAP TRUE
J 0
(-5650 2525);
DISPLAY 0.872340 (-5650 2525);
DISPLAY INVISIBLE (-5650 2525);
FORCEPROP 1 LAST PATH I45
J 0
(-5977 2650);
DISPLAY 0.872340 (-5977 2650);
PAINT GREEN (-5977 2650);
DISPLAY INVISIBLE (-5977 2650);
FORCEADD TAP..1
(-5975 2750);
FORCEPROP 3 LASTPIN (-6025 2750) SIG_NAME M_I_CPU1_SB_DQ<12>
J 0
(-6015 2760);
DISPLAY 0.659574 (-6015 2760);
PAINT MONO (-6015 2760);
DISPLAY INVISIBLE (-6015 2760);
FORCEPROP 1 LASTPIN (-6025 2750) BN 12
J 0
(-6037 2758);
DISPLAY 0.489362 (-6037 2758);
PAINT GREEN (-6037 2758);
FORCEPROP 2 LAST CDS_LIB mstr_standard
J 0
(-5975 2750);
DISPLAY 0.723404 (-5975 2750);
PAINT MONO (-5975 2750);
DISPLAY INVISIBLE (-5975 2750);
FORCEPROP 1 LAST BODY_TYPE PLUMBING
J 0
(-5975 2800);
DISPLAY 0.872340 (-5975 2800);
PAINT GREEN (-5975 2800);
DISPLAY INVISIBLE (-5975 2800);
FORCEPROP 1 LAST HDL_TAP TRUE
J 0
(-5650 2625);
DISPLAY 0.872340 (-5650 2625);
DISPLAY INVISIBLE (-5650 2625);
FORCEPROP 1 LAST PATH I46
J 0
(-5977 2750);
DISPLAY 0.872340 (-5977 2750);
PAINT GREEN (-5977 2750);
DISPLAY INVISIBLE (-5977 2750);
FORCEADD TAP..1
(-5975 2700);
FORCEPROP 3 LASTPIN (-6025 2700) SIG_NAME M_I_CPU1_SB_DQ<11>
J 0
(-6015 2710);
DISPLAY 0.659574 (-6015 2710);
PAINT MONO (-6015 2710);
DISPLAY INVISIBLE (-6015 2710);
FORCEPROP 1 LASTPIN (-6025 2700) BN 11
J 0
(-6037 2708);
DISPLAY 0.489362 (-6037 2708);
PAINT GREEN (-6037 2708);
FORCEPROP 2 LAST CDS_LIB mstr_standard
J 0
(-5975 2700);
DISPLAY 0.723404 (-5975 2700);
PAINT MONO (-5975 2700);
DISPLAY INVISIBLE (-5975 2700);
FORCEPROP 1 LAST BODY_TYPE PLUMBING
J 0
(-5975 2750);
DISPLAY 0.872340 (-5975 2750);
PAINT GREEN (-5975 2750);
DISPLAY INVISIBLE (-5975 2750);
FORCEPROP 1 LAST HDL_TAP TRUE
J 0
(-5650 2575);
DISPLAY 0.872340 (-5650 2575);
DISPLAY INVISIBLE (-5650 2575);
FORCEPROP 1 LAST PATH I47
J 0
(-5977 2700);
DISPLAY 0.872340 (-5977 2700);
PAINT GREEN (-5977 2700);
DISPLAY INVISIBLE (-5977 2700);
FORCEADD TAP..1
(-5975 2850);
FORCEPROP 3 LASTPIN (-6025 2850) SIG_NAME M_I_CPU1_SB_DQ<14>
J 0
(-6015 2860);
DISPLAY 0.659574 (-6015 2860);
PAINT MONO (-6015 2860);
DISPLAY INVISIBLE (-6015 2860);
FORCEPROP 1 LASTPIN (-6025 2850) BN 14
J 0
(-6037 2858);
DISPLAY 0.489362 (-6037 2858);
PAINT GREEN (-6037 2858);
FORCEPROP 2 LAST CDS_LIB mstr_standard
J 0
(-5975 2850);
DISPLAY 0.723404 (-5975 2850);
PAINT MONO (-5975 2850);
DISPLAY INVISIBLE (-5975 2850);
FORCEPROP 1 LAST BODY_TYPE PLUMBING
J 0
(-5975 2900);
DISPLAY 0.872340 (-5975 2900);
PAINT GREEN (-5975 2900);
DISPLAY INVISIBLE (-5975 2900);
FORCEPROP 1 LAST HDL_TAP TRUE
J 0
(-5650 2725);
DISPLAY 0.872340 (-5650 2725);
DISPLAY INVISIBLE (-5650 2725);
FORCEPROP 1 LAST PATH I48
J 0
(-5977 2850);
DISPLAY 0.872340 (-5977 2850);
PAINT GREEN (-5977 2850);
DISPLAY INVISIBLE (-5977 2850);
FORCEADD TAP..1
(-5975 2800);
FORCEPROP 3 LASTPIN (-6025 2800) SIG_NAME M_I_CPU1_SB_DQ<13>
J 0
(-6015 2810);
DISPLAY 0.659574 (-6015 2810);
PAINT MONO (-6015 2810);
DISPLAY INVISIBLE (-6015 2810);
FORCEPROP 1 LASTPIN (-6025 2800) BN 13
J 0
(-6037 2808);
DISPLAY 0.489362 (-6037 2808);
PAINT GREEN (-6037 2808);
FORCEPROP 2 LAST CDS_LIB mstr_standard
J 0
(-5975 2800);
DISPLAY 0.723404 (-5975 2800);
PAINT MONO (-5975 2800);
DISPLAY INVISIBLE (-5975 2800);
FORCEPROP 1 LAST BODY_TYPE PLUMBING
J 0
(-5975 2850);
DISPLAY 0.872340 (-5975 2850);
PAINT GREEN (-5975 2850);
DISPLAY INVISIBLE (-5975 2850);
FORCEPROP 1 LAST HDL_TAP TRUE
J 0
(-5650 2675);
DISPLAY 0.872340 (-5650 2675);
DISPLAY INVISIBLE (-5650 2675);
FORCEPROP 1 LAST PATH I49
J 0
(-5977 2800);
DISPLAY 0.872340 (-5977 2800);
PAINT GREEN (-5977 2800);
DISPLAY INVISIBLE (-5977 2800);
FORCEADD TAP..1
(-5975 2900);
FORCEPROP 3 LASTPIN (-6025 2900) SIG_NAME M_I_CPU1_SB_DQ<15>
J 0
(-6015 2910);
DISPLAY 0.659574 (-6015 2910);
PAINT MONO (-6015 2910);
DISPLAY INVISIBLE (-6015 2910);
FORCEPROP 1 LASTPIN (-6025 2900) BN 15
J 0
(-6037 2908);
DISPLAY 0.489362 (-6037 2908);
PAINT GREEN (-6037 2908);
FORCEPROP 2 LAST CDS_LIB mstr_standard
J 0
(-5975 2900);
DISPLAY 0.723404 (-5975 2900);
PAINT MONO (-5975 2900);
DISPLAY INVISIBLE (-5975 2900);
FORCEPROP 1 LAST BODY_TYPE PLUMBING
J 0
(-5975 2950);
DISPLAY 0.872340 (-5975 2950);
PAINT GREEN (-5975 2950);
DISPLAY INVISIBLE (-5975 2950);
FORCEPROP 1 LAST HDL_TAP TRUE
J 0
(-5650 2775);
DISPLAY 0.872340 (-5650 2775);
DISPLAY INVISIBLE (-5650 2775);
FORCEPROP 1 LAST PATH I50
J 0
(-5977 2900);
DISPLAY 0.872340 (-5977 2900);
PAINT GREEN (-5977 2900);
DISPLAY INVISIBLE (-5977 2900);
FORCEADD TAP..1
(-5975 3000);
FORCEPROP 3 LASTPIN (-6025 3000) SIG_NAME M_I_CPU1_SB_DQ<17>
J 0
(-6015 3010);
DISPLAY 0.659574 (-6015 3010);
PAINT MONO (-6015 3010);
DISPLAY INVISIBLE (-6015 3010);
FORCEPROP 1 LASTPIN (-6025 3000) BN 17
J 0
(-6037 3008);
DISPLAY 0.489362 (-6037 3008);
PAINT GREEN (-6037 3008);
FORCEPROP 2 LAST CDS_LIB mstr_standard
J 0
(-5975 3000);
DISPLAY 0.723404 (-5975 3000);
PAINT MONO (-5975 3000);
DISPLAY INVISIBLE (-5975 3000);
FORCEPROP 1 LAST BODY_TYPE PLUMBING
J 0
(-5975 3050);
DISPLAY 0.872340 (-5975 3050);
PAINT GREEN (-5975 3050);
DISPLAY INVISIBLE (-5975 3050);
FORCEPROP 1 LAST HDL_TAP TRUE
J 0
(-5650 2875);
DISPLAY 0.872340 (-5650 2875);
DISPLAY INVISIBLE (-5650 2875);
FORCEPROP 1 LAST PATH I51
J 0
(-5977 3000);
DISPLAY 0.872340 (-5977 3000);
PAINT GREEN (-5977 3000);
DISPLAY INVISIBLE (-5977 3000);
FORCEADD TAP..1
(-5975 2950);
FORCEPROP 3 LASTPIN (-6025 2950) SIG_NAME M_I_CPU1_SB_DQ<16>
J 0
(-6015 2960);
DISPLAY 0.659574 (-6015 2960);
PAINT MONO (-6015 2960);
DISPLAY INVISIBLE (-6015 2960);
FORCEPROP 1 LASTPIN (-6025 2950) BN 16
J 0
(-6037 2958);
DISPLAY 0.489362 (-6037 2958);
PAINT GREEN (-6037 2958);
FORCEPROP 2 LAST CDS_LIB mstr_standard
J 0
(-5975 2950);
DISPLAY 0.723404 (-5975 2950);
PAINT MONO (-5975 2950);
DISPLAY INVISIBLE (-5975 2950);
FORCEPROP 1 LAST BODY_TYPE PLUMBING
J 0
(-5975 3000);
DISPLAY 0.872340 (-5975 3000);
PAINT GREEN (-5975 3000);
DISPLAY INVISIBLE (-5975 3000);
FORCEPROP 1 LAST HDL_TAP TRUE
J 0
(-5650 2825);
DISPLAY 0.872340 (-5650 2825);
DISPLAY INVISIBLE (-5650 2825);
FORCEPROP 1 LAST PATH I52
J 0
(-5977 2950);
DISPLAY 0.872340 (-5977 2950);
PAINT GREEN (-5977 2950);
DISPLAY INVISIBLE (-5977 2950);
FORCEADD TAP..1
(-5975 3150);
FORCEPROP 3 LASTPIN (-6025 3150) SIG_NAME M_I_CPU1_SB_DQ<20>
J 0
(-6015 3160);
DISPLAY 0.659574 (-6015 3160);
PAINT MONO (-6015 3160);
DISPLAY INVISIBLE (-6015 3160);
FORCEPROP 1 LASTPIN (-6025 3150) BN 20
J 0
(-6037 3158);
DISPLAY 0.489362 (-6037 3158);
PAINT GREEN (-6037 3158);
FORCEPROP 2 LAST CDS_LIB mstr_standard
J 0
(-5975 3150);
DISPLAY 0.723404 (-5975 3150);
PAINT MONO (-5975 3150);
DISPLAY INVISIBLE (-5975 3150);
FORCEPROP 1 LAST BODY_TYPE PLUMBING
J 0
(-5975 3200);
DISPLAY 0.872340 (-5975 3200);
PAINT GREEN (-5975 3200);
DISPLAY INVISIBLE (-5975 3200);
FORCEPROP 1 LAST HDL_TAP TRUE
J 0
(-5650 3025);
DISPLAY 0.872340 (-5650 3025);
DISPLAY INVISIBLE (-5650 3025);
FORCEPROP 1 LAST PATH I53
J 0
(-5977 3150);
DISPLAY 0.872340 (-5977 3150);
PAINT GREEN (-5977 3150);
DISPLAY INVISIBLE (-5977 3150);
FORCEADD TAP..1
(-5975 3100);
FORCEPROP 3 LASTPIN (-6025 3100) SIG_NAME M_I_CPU1_SB_DQ<19>
J 0
(-6015 3110);
DISPLAY 0.659574 (-6015 3110);
PAINT MONO (-6015 3110);
DISPLAY INVISIBLE (-6015 3110);
FORCEPROP 1 LASTPIN (-6025 3100) BN 19
J 0
(-6037 3108);
DISPLAY 0.489362 (-6037 3108);
PAINT GREEN (-6037 3108);
FORCEPROP 2 LAST CDS_LIB mstr_standard
J 0
(-5975 3100);
DISPLAY 0.723404 (-5975 3100);
PAINT MONO (-5975 3100);
DISPLAY INVISIBLE (-5975 3100);
FORCEPROP 1 LAST BODY_TYPE PLUMBING
J 0
(-5975 3150);
DISPLAY 0.872340 (-5975 3150);
PAINT GREEN (-5975 3150);
DISPLAY INVISIBLE (-5975 3150);
FORCEPROP 1 LAST HDL_TAP TRUE
J 0
(-5650 2975);
DISPLAY 0.872340 (-5650 2975);
DISPLAY INVISIBLE (-5650 2975);
FORCEPROP 1 LAST PATH I54
J 0
(-5977 3100);
DISPLAY 0.872340 (-5977 3100);
PAINT GREEN (-5977 3100);
DISPLAY INVISIBLE (-5977 3100);
FORCEADD TAP..1
(-5975 3050);
FORCEPROP 3 LASTPIN (-6025 3050) SIG_NAME M_I_CPU1_SB_DQ<18>
J 0
(-6015 3060);
DISPLAY 0.659574 (-6015 3060);
PAINT MONO (-6015 3060);
DISPLAY INVISIBLE (-6015 3060);
FORCEPROP 1 LASTPIN (-6025 3050) BN 18
J 0
(-6037 3058);
DISPLAY 0.489362 (-6037 3058);
PAINT GREEN (-6037 3058);
FORCEPROP 2 LAST CDS_LIB mstr_standard
J 0
(-5975 3050);
DISPLAY 0.723404 (-5975 3050);
PAINT MONO (-5975 3050);
DISPLAY INVISIBLE (-5975 3050);
FORCEPROP 1 LAST BODY_TYPE PLUMBING
J 0
(-5975 3100);
DISPLAY 0.872340 (-5975 3100);
PAINT GREEN (-5975 3100);
DISPLAY INVISIBLE (-5975 3100);
FORCEPROP 1 LAST HDL_TAP TRUE
J 0
(-5650 2925);
DISPLAY 0.872340 (-5650 2925);
DISPLAY INVISIBLE (-5650 2925);
FORCEPROP 1 LAST PATH I55
J 0
(-5977 3050);
DISPLAY 0.872340 (-5977 3050);
PAINT GREEN (-5977 3050);
DISPLAY INVISIBLE (-5977 3050);
FORCEADD TAP..1
(-5975 3200);
FORCEPROP 3 LASTPIN (-6025 3200) SIG_NAME M_I_CPU1_SB_DQ<21>
J 0
(-6015 3210);
DISPLAY 0.659574 (-6015 3210);
PAINT MONO (-6015 3210);
DISPLAY INVISIBLE (-6015 3210);
FORCEPROP 1 LASTPIN (-6025 3200) BN 21
J 0
(-6037 3208);
DISPLAY 0.489362 (-6037 3208);
PAINT GREEN (-6037 3208);
FORCEPROP 2 LAST CDS_LIB mstr_standard
J 0
(-5975 3200);
DISPLAY 0.723404 (-5975 3200);
PAINT MONO (-5975 3200);
DISPLAY INVISIBLE (-5975 3200);
FORCEPROP 1 LAST BODY_TYPE PLUMBING
J 0
(-5975 3250);
DISPLAY 0.872340 (-5975 3250);
PAINT GREEN (-5975 3250);
DISPLAY INVISIBLE (-5975 3250);
FORCEPROP 1 LAST HDL_TAP TRUE
J 0
(-5650 3075);
DISPLAY 0.872340 (-5650 3075);
DISPLAY INVISIBLE (-5650 3075);
FORCEPROP 1 LAST PATH I56
J 0
(-5977 3200);
DISPLAY 0.872340 (-5977 3200);
PAINT GREEN (-5977 3200);
DISPLAY INVISIBLE (-5977 3200);
FORCEADD TAP..1
(-5975 3250);
FORCEPROP 3 LASTPIN (-6025 3250) SIG_NAME M_I_CPU1_SB_DQ<22>
J 0
(-6015 3260);
DISPLAY 0.659574 (-6015 3260);
PAINT MONO (-6015 3260);
DISPLAY INVISIBLE (-6015 3260);
FORCEPROP 1 LASTPIN (-6025 3250) BN 22
J 0
(-6037 3258);
DISPLAY 0.489362 (-6037 3258);
PAINT GREEN (-6037 3258);
FORCEPROP 2 LAST CDS_LIB mstr_standard
J 0
(-5975 3250);
DISPLAY 0.723404 (-5975 3250);
PAINT MONO (-5975 3250);
DISPLAY INVISIBLE (-5975 3250);
FORCEPROP 1 LAST BODY_TYPE PLUMBING
J 0
(-5975 3300);
DISPLAY 0.872340 (-5975 3300);
PAINT GREEN (-5975 3300);
DISPLAY INVISIBLE (-5975 3300);
FORCEPROP 1 LAST HDL_TAP TRUE
J 0
(-5650 3125);
DISPLAY 0.872340 (-5650 3125);
DISPLAY INVISIBLE (-5650 3125);
FORCEPROP 1 LAST PATH I57
J 0
(-5977 3250);
DISPLAY 0.872340 (-5977 3250);
PAINT GREEN (-5977 3250);
DISPLAY INVISIBLE (-5977 3250);
FORCEADD TAP..1
(-5975 3400);
FORCEPROP 3 LASTPIN (-6025 3400) SIG_NAME M_I_CPU1_SB_DQ<25>
J 0
(-6015 3410);
DISPLAY 0.659574 (-6015 3410);
PAINT MONO (-6015 3410);
DISPLAY INVISIBLE (-6015 3410);
FORCEPROP 1 LASTPIN (-6025 3400) BN 25
J 0
(-6037 3408);
DISPLAY 0.489362 (-6037 3408);
PAINT GREEN (-6037 3408);
FORCEPROP 2 LAST CDS_LIB mstr_standard
J 0
(-5975 3400);
DISPLAY 0.723404 (-5975 3400);
PAINT MONO (-5975 3400);
DISPLAY INVISIBLE (-5975 3400);
FORCEPROP 1 LAST BODY_TYPE PLUMBING
J 0
(-5975 3450);
DISPLAY 0.872340 (-5975 3450);
PAINT GREEN (-5975 3450);
DISPLAY INVISIBLE (-5975 3450);
FORCEPROP 1 LAST HDL_TAP TRUE
J 0
(-5650 3275);
DISPLAY 0.872340 (-5650 3275);
DISPLAY INVISIBLE (-5650 3275);
FORCEPROP 1 LAST PATH I58
J 0
(-5977 3400);
DISPLAY 0.872340 (-5977 3400);
PAINT GREEN (-5977 3400);
DISPLAY INVISIBLE (-5977 3400);
FORCEADD TAP..1
(-5975 3350);
FORCEPROP 3 LASTPIN (-6025 3350) SIG_NAME M_I_CPU1_SB_DQ<24>
J 0
(-6015 3360);
DISPLAY 0.659574 (-6015 3360);
PAINT MONO (-6015 3360);
DISPLAY INVISIBLE (-6015 3360);
FORCEPROP 1 LASTPIN (-6025 3350) BN 24
J 0
(-6037 3358);
DISPLAY 0.489362 (-6037 3358);
PAINT GREEN (-6037 3358);
FORCEPROP 2 LAST CDS_LIB mstr_standard
J 0
(-5975 3350);
DISPLAY 0.723404 (-5975 3350);
PAINT MONO (-5975 3350);
DISPLAY INVISIBLE (-5975 3350);
FORCEPROP 1 LAST BODY_TYPE PLUMBING
J 0
(-5975 3400);
DISPLAY 0.872340 (-5975 3400);
PAINT GREEN (-5975 3400);
DISPLAY INVISIBLE (-5975 3400);
FORCEPROP 1 LAST HDL_TAP TRUE
J 0
(-5650 3225);
DISPLAY 0.872340 (-5650 3225);
DISPLAY INVISIBLE (-5650 3225);
FORCEPROP 1 LAST PATH I59
J 0
(-5977 3350);
DISPLAY 0.872340 (-5977 3350);
PAINT GREEN (-5977 3350);
DISPLAY INVISIBLE (-5977 3350);
FORCEADD OFFPAGE..1
(-8675 2850);
FORCEPROP 2 LAST $XR0 106 
J 0
(-8927 2850);
DISPLAY 0.638298 (-8927 2850);
PAINT MONO (-8927 2850);
FORCEPROP 2 LAST CDS_LIB mstr_standard
J 0
(-8675 2850);
DISPLAY 0.808511 (-8675 2850);
DISPLAY INVISIBLE (-8675 2850);
FORCEPROP 1 LAST OFFPAGE TRUE
J 0
(-8350 2725);
DISPLAY 0.872340 (-8350 2725);
PAINT GREEN (-8350 2725);
DISPLAY INVISIBLE (-8350 2725);
FORCEPROP 1 LAST COMMENT_BODY TRUE
J 0
(-8550 2750);
DISPLAY 0.872340 (-8550 2750);
PAINT GREEN (-8550 2750);
DISPLAY INVISIBLE (-8550 2750);
FORCEPROP 2 LAST PATH I6
J 0
(-8950 2900);
DISPLAY 1.021277 (-8950 2900);
DISPLAY INVISIBLE (-8950 2900);
FORCEADD TAP..1
(-5975 3300);
FORCEPROP 3 LASTPIN (-6025 3300) SIG_NAME M_I_CPU1_SB_DQ<23>
J 0
(-6015 3310);
DISPLAY 0.659574 (-6015 3310);
PAINT MONO (-6015 3310);
DISPLAY INVISIBLE (-6015 3310);
FORCEPROP 1 LASTPIN (-6025 3300) BN 23
J 0
(-6037 3308);
DISPLAY 0.489362 (-6037 3308);
PAINT GREEN (-6037 3308);
FORCEPROP 2 LAST CDS_LIB mstr_standard
J 0
(-5975 3300);
DISPLAY 0.723404 (-5975 3300);
PAINT MONO (-5975 3300);
DISPLAY INVISIBLE (-5975 3300);
FORCEPROP 1 LAST BODY_TYPE PLUMBING
J 0
(-5975 3350);
DISPLAY 0.872340 (-5975 3350);
PAINT GREEN (-5975 3350);
DISPLAY INVISIBLE (-5975 3350);
FORCEPROP 1 LAST HDL_TAP TRUE
J 0
(-5650 3175);
DISPLAY 0.872340 (-5650 3175);
DISPLAY INVISIBLE (-5650 3175);
FORCEPROP 1 LAST PATH I60
J 0
(-5977 3300);
DISPLAY 0.872340 (-5977 3300);
PAINT GREEN (-5977 3300);
DISPLAY INVISIBLE (-5977 3300);
FORCEADD TAP..1
(-5975 3450);
FORCEPROP 3 LASTPIN (-6025 3450) SIG_NAME M_I_CPU1_SB_DQ<26>
J 0
(-6015 3460);
DISPLAY 0.659574 (-6015 3460);
PAINT MONO (-6015 3460);
DISPLAY INVISIBLE (-6015 3460);
FORCEPROP 1 LASTPIN (-6025 3450) BN 26
J 0
(-6037 3458);
DISPLAY 0.489362 (-6037 3458);
PAINT GREEN (-6037 3458);
FORCEPROP 2 LAST CDS_LIB mstr_standard
J 0
(-5975 3450);
DISPLAY 0.723404 (-5975 3450);
PAINT MONO (-5975 3450);
DISPLAY INVISIBLE (-5975 3450);
FORCEPROP 1 LAST BODY_TYPE PLUMBING
J 0
(-5975 3500);
DISPLAY 0.872340 (-5975 3500);
PAINT GREEN (-5975 3500);
DISPLAY INVISIBLE (-5975 3500);
FORCEPROP 1 LAST HDL_TAP TRUE
J 0
(-5650 3325);
DISPLAY 0.872340 (-5650 3325);
DISPLAY INVISIBLE (-5650 3325);
FORCEPROP 1 LAST PATH I61
J 0
(-5977 3450);
DISPLAY 0.872340 (-5977 3450);
PAINT GREEN (-5977 3450);
DISPLAY INVISIBLE (-5977 3450);
FORCEADD TAP..1
(-5975 3500);
FORCEPROP 3 LASTPIN (-6025 3500) SIG_NAME M_I_CPU1_SB_DQ<27>
J 0
(-6015 3510);
DISPLAY 0.659574 (-6015 3510);
PAINT MONO (-6015 3510);
DISPLAY INVISIBLE (-6015 3510);
FORCEPROP 1 LASTPIN (-6025 3500) BN 27
J 0
(-6037 3508);
DISPLAY 0.489362 (-6037 3508);
PAINT GREEN (-6037 3508);
FORCEPROP 2 LAST CDS_LIB mstr_standard
J 0
(-5975 3500);
DISPLAY 0.723404 (-5975 3500);
PAINT MONO (-5975 3500);
DISPLAY INVISIBLE (-5975 3500);
FORCEPROP 1 LAST BODY_TYPE PLUMBING
J 0
(-5975 3550);
DISPLAY 0.872340 (-5975 3550);
PAINT GREEN (-5975 3550);
DISPLAY INVISIBLE (-5975 3550);
FORCEPROP 1 LAST HDL_TAP TRUE
J 0
(-5650 3375);
DISPLAY 0.872340 (-5650 3375);
DISPLAY INVISIBLE (-5650 3375);
FORCEPROP 1 LAST PATH I62
J 0
(-5977 3500);
DISPLAY 0.872340 (-5977 3500);
PAINT GREEN (-5977 3500);
DISPLAY INVISIBLE (-5977 3500);
FORCEADD TAP..1
(-5975 3650);
FORCEPROP 3 LASTPIN (-6025 3650) SIG_NAME M_I_CPU1_SB_DQ<30>
J 0
(-6015 3660);
DISPLAY 0.659574 (-6015 3660);
PAINT MONO (-6015 3660);
DISPLAY INVISIBLE (-6015 3660);
FORCEPROP 1 LASTPIN (-6025 3650) BN 30
J 0
(-6037 3658);
DISPLAY 0.489362 (-6037 3658);
PAINT GREEN (-6037 3658);
FORCEPROP 2 LAST CDS_LIB mstr_standard
J 0
(-5975 3650);
DISPLAY 0.723404 (-5975 3650);
PAINT MONO (-5975 3650);
DISPLAY INVISIBLE (-5975 3650);
FORCEPROP 1 LAST BODY_TYPE PLUMBING
J 0
(-5975 3700);
DISPLAY 0.872340 (-5975 3700);
PAINT GREEN (-5975 3700);
DISPLAY INVISIBLE (-5975 3700);
FORCEPROP 1 LAST HDL_TAP TRUE
J 0
(-5650 3525);
DISPLAY 0.872340 (-5650 3525);
DISPLAY INVISIBLE (-5650 3525);
FORCEPROP 1 LAST PATH I63
J 0
(-5977 3650);
DISPLAY 0.872340 (-5977 3650);
PAINT GREEN (-5977 3650);
DISPLAY INVISIBLE (-5977 3650);
FORCEADD TAP..1
(-5975 3600);
FORCEPROP 3 LASTPIN (-6025 3600) SIG_NAME M_I_CPU1_SB_DQ<29>
J 0
(-6015 3610);
DISPLAY 0.659574 (-6015 3610);
PAINT MONO (-6015 3610);
DISPLAY INVISIBLE (-6015 3610);
FORCEPROP 1 LASTPIN (-6025 3600) BN 29
J 0
(-6037 3608);
DISPLAY 0.489362 (-6037 3608);
PAINT GREEN (-6037 3608);
FORCEPROP 2 LAST CDS_LIB mstr_standard
J 0
(-5975 3600);
DISPLAY 0.723404 (-5975 3600);
PAINT MONO (-5975 3600);
DISPLAY INVISIBLE (-5975 3600);
FORCEPROP 1 LAST BODY_TYPE PLUMBING
J 0
(-5975 3650);
DISPLAY 0.872340 (-5975 3650);
PAINT GREEN (-5975 3650);
DISPLAY INVISIBLE (-5975 3650);
FORCEPROP 1 LAST HDL_TAP TRUE
J 0
(-5650 3475);
DISPLAY 0.872340 (-5650 3475);
DISPLAY INVISIBLE (-5650 3475);
FORCEPROP 1 LAST PATH I64
J 0
(-5977 3600);
DISPLAY 0.872340 (-5977 3600);
PAINT GREEN (-5977 3600);
DISPLAY INVISIBLE (-5977 3600);
FORCEADD TAP..1
(-5975 3550);
FORCEPROP 3 LASTPIN (-6025 3550) SIG_NAME M_I_CPU1_SB_DQ<28>
J 0
(-6015 3560);
DISPLAY 0.659574 (-6015 3560);
PAINT MONO (-6015 3560);
DISPLAY INVISIBLE (-6015 3560);
FORCEPROP 1 LASTPIN (-6025 3550) BN 28
J 0
(-6037 3558);
DISPLAY 0.489362 (-6037 3558);
PAINT GREEN (-6037 3558);
FORCEPROP 2 LAST CDS_LIB mstr_standard
J 0
(-5975 3550);
DISPLAY 0.723404 (-5975 3550);
PAINT MONO (-5975 3550);
DISPLAY INVISIBLE (-5975 3550);
FORCEPROP 1 LAST BODY_TYPE PLUMBING
J 0
(-5975 3600);
DISPLAY 0.872340 (-5975 3600);
PAINT GREEN (-5975 3600);
DISPLAY INVISIBLE (-5975 3600);
FORCEPROP 1 LAST HDL_TAP TRUE
J 0
(-5650 3425);
DISPLAY 0.872340 (-5650 3425);
DISPLAY INVISIBLE (-5650 3425);
FORCEPROP 1 LAST PATH I65
J 0
(-5977 3550);
DISPLAY 0.872340 (-5977 3550);
PAINT GREEN (-5977 3550);
DISPLAY INVISIBLE (-5977 3550);
FORCEADD TAP..1
(-5975 3700);
FORCEPROP 3 LASTPIN (-6025 3700) SIG_NAME M_I_CPU1_SB_DQ<31>
J 0
(-6015 3710);
DISPLAY 0.659574 (-6015 3710);
PAINT MONO (-6015 3710);
DISPLAY INVISIBLE (-6015 3710);
FORCEPROP 1 LASTPIN (-6025 3700) BN 31
J 0
(-6037 3708);
DISPLAY 0.489362 (-6037 3708);
PAINT GREEN (-6037 3708);
FORCEPROP 2 LAST CDS_LIB mstr_standard
J 0
(-5975 3700);
DISPLAY 0.723404 (-5975 3700);
PAINT MONO (-5975 3700);
DISPLAY INVISIBLE (-5975 3700);
FORCEPROP 1 LAST BODY_TYPE PLUMBING
J 0
(-5975 3750);
DISPLAY 0.872340 (-5975 3750);
PAINT GREEN (-5975 3750);
DISPLAY INVISIBLE (-5975 3750);
FORCEPROP 1 LAST HDL_TAP TRUE
J 0
(-5650 3575);
DISPLAY 0.872340 (-5650 3575);
DISPLAY INVISIBLE (-5650 3575);
FORCEPROP 1 LAST PATH I66
J 0
(-5977 3700);
DISPLAY 0.872340 (-5977 3700);
PAINT GREEN (-5977 3700);
DISPLAY INVISIBLE (-5977 3700);
FORCEADD OFFPAGE..5
(-8125 3000);
FORCEPROP 2 LAST $XR0 45 
J 0
(-8349 3000);
DISPLAY 0.638298 (-8349 3000);
PAINT MONO (-8349 3000);
FORCEPROP 2 LAST CDS_LIB mstr_standard
J 0
(-8125 3000);
DISPLAY INVISIBLE (-8125 3000);
FORCEPROP 1 LAST OFFPAGE TRUE
J 0
(-7800 2875);
DISPLAY 0.872340 (-7800 2875);
PAINT GREEN (-7800 2875);
DISPLAY INVISIBLE (-7800 2875);
FORCEPROP 1 LAST COMMENT_BODY TRUE
J 0
(-8025 2925);
DISPLAY 0.872340 (-8025 2925);
PAINT GREEN (-8025 2925);
DISPLAY INVISIBLE (-8025 2925);
FORCEPROP 2 LAST PATH I7
J 0
(-8450 3050);
DISPLAY 1.021277 (-8450 3050);
DISPLAY INVISIBLE (-8450 3050);
FORCEADD OFFPAGE..3
(-5275 3750);
FORCEPROP 2 LAST $XR0 45 
J 0
(-4971 3750);
DISPLAY 0.638298 (-4971 3750);
PAINT MONO (-4971 3750);
FORCEPROP 2 LAST CDS_LIB mstr_standard
J 0
(-5275 3750);
DISPLAY 0.723404 (-5275 3750);
PAINT MONO (-5275 3750);
DISPLAY INVISIBLE (-5275 3750);
FORCEPROP 1 LAST OFFPAGE TRUE
J 0
(-4950 3625);
DISPLAY 0.872340 (-4950 3625);
PAINT GREEN (-4950 3625);
DISPLAY INVISIBLE (-4950 3625);
FORCEPROP 1 LAST COMMENT_BODY TRUE
J 0
(-5325 3650);
DISPLAY 0.872340 (-5325 3650);
PAINT GREEN (-5325 3650);
DISPLAY INVISIBLE (-5325 3650);
FORCEPROP 2 LAST PATH I74
J 0
(-5050 3800);
DISPLAY 1.021277 (-5050 3800);
DISPLAY INVISIBLE (-5050 3800);
FORCEADD TAP..1
R 2
(-7675 3800);
FORCEPROP 3 LASTPIN (-7625 3800) SIG_NAME M_I_CPU1_SA_CB<4>
J 0
(-7615 3810);
DISPLAY 0.659574 (-7615 3810);
PAINT MONO (-7615 3810);
DISPLAY INVISIBLE (-7615 3810);
FORCEPROP 1 LASTPIN (-7625 3800) BN 4
J 2
(-7613 3808);
DISPLAY 0.489362 (-7613 3808);
PAINT GREEN (-7613 3808);
FORCEPROP 2 LAST CDS_LIB mstr_standard
J 0
(-7675 3800);
DISPLAY 0.723404 (-7675 3800);
PAINT MONO (-7675 3800);
DISPLAY INVISIBLE (-7675 3800);
FORCEPROP 1 LAST BODY_TYPE PLUMBING
J 2
(-7675 3850);
DISPLAY 0.872340 (-7675 3850);
PAINT GREEN (-7675 3850);
DISPLAY INVISIBLE (-7675 3850);
FORCEPROP 1 LAST HDL_TAP TRUE
J 2
(-8000 3675);
DISPLAY 0.872340 (-8000 3675);
DISPLAY INVISIBLE (-8000 3675);
FORCEPROP 1 LAST PATH I75
J 2
(-7673 3800);
DISPLAY 0.872340 (-7673 3800);
PAINT GREEN (-7673 3800);
DISPLAY INVISIBLE (-7673 3800);
FORCEADD TAP..1
R 2
(-7675 3850);
FORCEPROP 3 LASTPIN (-7625 3850) SIG_NAME M_I_CPU1_SA_CB<5>
J 0
(-7615 3860);
DISPLAY 0.659574 (-7615 3860);
PAINT MONO (-7615 3860);
DISPLAY INVISIBLE (-7615 3860);
FORCEPROP 1 LASTPIN (-7625 3850) BN 5
J 2
(-7613 3858);
DISPLAY 0.489362 (-7613 3858);
PAINT GREEN (-7613 3858);
FORCEPROP 2 LAST CDS_LIB mstr_standard
J 0
(-7675 3850);
DISPLAY 0.723404 (-7675 3850);
PAINT MONO (-7675 3850);
DISPLAY INVISIBLE (-7675 3850);
FORCEPROP 1 LAST BODY_TYPE PLUMBING
J 2
(-7675 3900);
DISPLAY 0.872340 (-7675 3900);
PAINT GREEN (-7675 3900);
DISPLAY INVISIBLE (-7675 3900);
FORCEPROP 1 LAST HDL_TAP TRUE
J 2
(-8000 3725);
DISPLAY 0.872340 (-8000 3725);
DISPLAY INVISIBLE (-8000 3725);
FORCEPROP 1 LAST PATH I76
J 2
(-7673 3850);
DISPLAY 0.872340 (-7673 3850);
PAINT GREEN (-7673 3850);
DISPLAY INVISIBLE (-7673 3850);
FORCEADD TAP..1
R 2
(-7675 3900);
FORCEPROP 3 LASTPIN (-7625 3900) SIG_NAME M_I_CPU1_SA_CB<6>
J 0
(-7615 3910);
DISPLAY 0.659574 (-7615 3910);
PAINT MONO (-7615 3910);
DISPLAY INVISIBLE (-7615 3910);
FORCEPROP 1 LASTPIN (-7625 3900) BN 6
J 2
(-7613 3908);
DISPLAY 0.489362 (-7613 3908);
PAINT GREEN (-7613 3908);
FORCEPROP 2 LAST CDS_LIB mstr_standard
J 0
(-7675 3900);
DISPLAY 0.723404 (-7675 3900);
PAINT MONO (-7675 3900);
DISPLAY INVISIBLE (-7675 3900);
FORCEPROP 1 LAST BODY_TYPE PLUMBING
J 2
(-7675 3950);
DISPLAY 0.872340 (-7675 3950);
PAINT GREEN (-7675 3950);
DISPLAY INVISIBLE (-7675 3950);
FORCEPROP 1 LAST HDL_TAP TRUE
J 2
(-8000 3775);
DISPLAY 0.872340 (-8000 3775);
DISPLAY INVISIBLE (-8000 3775);
FORCEPROP 1 LAST PATH I77
J 2
(-7673 3900);
DISPLAY 0.872340 (-7673 3900);
PAINT GREEN (-7673 3900);
DISPLAY INVISIBLE (-7673 3900);
FORCEADD TAP..1
R 2
(-7675 3950);
FORCEPROP 3 LASTPIN (-7625 3950) SIG_NAME M_I_CPU1_SA_CB<7>
J 0
(-7615 3960);
DISPLAY 0.659574 (-7615 3960);
PAINT MONO (-7615 3960);
DISPLAY INVISIBLE (-7615 3960);
FORCEPROP 1 LASTPIN (-7625 3950) BN 7
J 2
(-7613 3958);
DISPLAY 0.489362 (-7613 3958);
PAINT GREEN (-7613 3958);
FORCEPROP 2 LAST CDS_LIB mstr_standard
J 0
(-7675 3950);
DISPLAY 0.723404 (-7675 3950);
PAINT MONO (-7675 3950);
DISPLAY INVISIBLE (-7675 3950);
FORCEPROP 1 LAST BODY_TYPE PLUMBING
J 2
(-7675 4000);
DISPLAY 0.872340 (-7675 4000);
PAINT GREEN (-7675 4000);
DISPLAY INVISIBLE (-7675 4000);
FORCEPROP 1 LAST HDL_TAP TRUE
J 2
(-8000 3825);
DISPLAY 0.872340 (-8000 3825);
DISPLAY INVISIBLE (-8000 3825);
FORCEPROP 1 LAST PATH I78
J 2
(-7673 3950);
DISPLAY 0.872340 (-7673 3950);
PAINT GREEN (-7673 3950);
DISPLAY INVISIBLE (-7673 3950);
FORCEADD TAP..1
R 2
(-7675 4650);
FORCEPROP 3 LASTPIN (-7625 4650) SIG_NAME M_I_CPU1_SB_CA<0>
J 0
(-7615 4660);
DISPLAY 0.659574 (-7615 4660);
PAINT MONO (-7615 4660);
DISPLAY INVISIBLE (-7615 4660);
FORCEPROP 1 LASTPIN (-7625 4650) BN 0
J 2
(-7613 4658);
DISPLAY 0.489362 (-7613 4658);
PAINT GREEN (-7613 4658);
FORCEPROP 2 LAST CDS_LIB mstr_standard
J 0
(-7675 4650);
DISPLAY 0.723404 (-7675 4650);
PAINT MONO (-7675 4650);
DISPLAY INVISIBLE (-7675 4650);
FORCEPROP 1 LAST BODY_TYPE PLUMBING
J 2
(-7675 4700);
DISPLAY 0.872340 (-7675 4700);
PAINT GREEN (-7675 4700);
DISPLAY INVISIBLE (-7675 4700);
FORCEPROP 1 LAST HDL_TAP TRUE
J 2
(-8000 4525);
DISPLAY 0.872340 (-8000 4525);
DISPLAY INVISIBLE (-8000 4525);
FORCEPROP 1 LAST PATH I79
J 2
(-7673 4650);
DISPLAY 0.872340 (-7673 4650);
PAINT GREEN (-7673 4650);
DISPLAY INVISIBLE (-7673 4650);
FORCEADD OFFPAGE..1
(-8125 3050);
FORCEPROP 2 LAST $XR0 45 
J 0
(-8376 3050);
DISPLAY 0.638298 (-8376 3050);
PAINT MONO (-8376 3050);
FORCEPROP 2 LAST CDS_LIB mstr_standard
J 0
(-8125 3050);
DISPLAY 0.808511 (-8125 3050);
DISPLAY INVISIBLE (-8125 3050);
FORCEPROP 1 LAST OFFPAGE TRUE
J 0
(-7800 2925);
DISPLAY 0.872340 (-7800 2925);
PAINT GREEN (-7800 2925);
DISPLAY INVISIBLE (-7800 2925);
FORCEPROP 1 LAST COMMENT_BODY TRUE
J 0
(-8000 2950);
DISPLAY 0.872340 (-8000 2950);
PAINT GREEN (-8000 2950);
DISPLAY INVISIBLE (-8000 2950);
FORCEPROP 2 LAST PATH I8
J 0
(-8325 3100);
DISPLAY 1.021277 (-8325 3100);
DISPLAY INVISIBLE (-8325 3100);
FORCEADD TAP..1
R 2
(-7675 4700);
FORCEPROP 3 LASTPIN (-7625 4700) SIG_NAME M_I_CPU1_SB_CA<1>
J 0
(-7615 4710);
DISPLAY 0.659574 (-7615 4710);
PAINT MONO (-7615 4710);
DISPLAY INVISIBLE (-7615 4710);
FORCEPROP 1 LASTPIN (-7625 4700) BN 1
J 2
(-7613 4708);
DISPLAY 0.489362 (-7613 4708);
PAINT GREEN (-7613 4708);
FORCEPROP 2 LAST CDS_LIB mstr_standard
J 0
(-7675 4700);
DISPLAY 0.723404 (-7675 4700);
PAINT MONO (-7675 4700);
DISPLAY INVISIBLE (-7675 4700);
FORCEPROP 1 LAST BODY_TYPE PLUMBING
J 2
(-7675 4750);
DISPLAY 0.872340 (-7675 4750);
PAINT GREEN (-7675 4750);
DISPLAY INVISIBLE (-7675 4750);
FORCEPROP 1 LAST HDL_TAP TRUE
J 2
(-8000 4575);
DISPLAY 0.872340 (-8000 4575);
DISPLAY INVISIBLE (-8000 4575);
FORCEPROP 1 LAST PATH I80
J 2
(-7673 4700);
DISPLAY 0.872340 (-7673 4700);
PAINT GREEN (-7673 4700);
DISPLAY INVISIBLE (-7673 4700);
FORCEADD TAP..1
R 2
(-7675 4750);
FORCEPROP 3 LASTPIN (-7625 4750) SIG_NAME M_I_CPU1_SB_CA<2>
J 0
(-7615 4760);
DISPLAY 0.659574 (-7615 4760);
PAINT MONO (-7615 4760);
DISPLAY INVISIBLE (-7615 4760);
FORCEPROP 1 LASTPIN (-7625 4750) BN 2
J 2
(-7613 4758);
DISPLAY 0.489362 (-7613 4758);
PAINT GREEN (-7613 4758);
FORCEPROP 2 LAST CDS_LIB mstr_standard
J 0
(-7675 4750);
DISPLAY 0.723404 (-7675 4750);
PAINT MONO (-7675 4750);
DISPLAY INVISIBLE (-7675 4750);
FORCEPROP 1 LAST BODY_TYPE PLUMBING
J 2
(-7675 4800);
DISPLAY 0.872340 (-7675 4800);
PAINT GREEN (-7675 4800);
DISPLAY INVISIBLE (-7675 4800);
FORCEPROP 1 LAST HDL_TAP TRUE
J 2
(-8000 4625);
DISPLAY 0.872340 (-8000 4625);
DISPLAY INVISIBLE (-8000 4625);
FORCEPROP 1 LAST PATH I81
J 2
(-7673 4750);
DISPLAY 0.872340 (-7673 4750);
PAINT GREEN (-7673 4750);
DISPLAY INVISIBLE (-7673 4750);
FORCEADD TAP..1
R 2
(-7675 4800);
FORCEPROP 3 LASTPIN (-7625 4800) SIG_NAME M_I_CPU1_SB_CA<3>
J 0
(-7615 4810);
DISPLAY 0.659574 (-7615 4810);
PAINT MONO (-7615 4810);
DISPLAY INVISIBLE (-7615 4810);
FORCEPROP 1 LASTPIN (-7625 4800) BN 3
J 2
(-7613 4808);
DISPLAY 0.489362 (-7613 4808);
PAINT GREEN (-7613 4808);
FORCEPROP 2 LAST CDS_LIB mstr_standard
J 0
(-7675 4800);
DISPLAY 0.723404 (-7675 4800);
PAINT MONO (-7675 4800);
DISPLAY INVISIBLE (-7675 4800);
FORCEPROP 1 LAST BODY_TYPE PLUMBING
J 2
(-7675 4850);
DISPLAY 0.872340 (-7675 4850);
PAINT GREEN (-7675 4850);
DISPLAY INVISIBLE (-7675 4850);
FORCEPROP 1 LAST HDL_TAP TRUE
J 2
(-8000 4675);
DISPLAY 0.872340 (-8000 4675);
DISPLAY INVISIBLE (-8000 4675);
FORCEPROP 1 LAST PATH I82
J 2
(-7673 4800);
DISPLAY 0.872340 (-7673 4800);
PAINT GREEN (-7673 4800);
DISPLAY INVISIBLE (-7673 4800);
FORCEADD TAP..1
R 2
(-7675 4850);
FORCEPROP 3 LASTPIN (-7625 4850) SIG_NAME M_I_CPU1_SB_CA<4>
J 0
(-7615 4860);
DISPLAY 0.659574 (-7615 4860);
PAINT MONO (-7615 4860);
DISPLAY INVISIBLE (-7615 4860);
FORCEPROP 1 LASTPIN (-7625 4850) BN 4
J 2
(-7613 4858);
DISPLAY 0.489362 (-7613 4858);
PAINT GREEN (-7613 4858);
FORCEPROP 2 LAST CDS_LIB mstr_standard
J 0
(-7675 4850);
DISPLAY 0.723404 (-7675 4850);
PAINT MONO (-7675 4850);
DISPLAY INVISIBLE (-7675 4850);
FORCEPROP 1 LAST BODY_TYPE PLUMBING
J 2
(-7675 4900);
DISPLAY 0.872340 (-7675 4900);
PAINT GREEN (-7675 4900);
DISPLAY INVISIBLE (-7675 4900);
FORCEPROP 1 LAST HDL_TAP TRUE
J 2
(-8000 4725);
DISPLAY 0.872340 (-8000 4725);
DISPLAY INVISIBLE (-8000 4725);
FORCEPROP 1 LAST PATH I83
J 2
(-7673 4850);
DISPLAY 0.872340 (-7673 4850);
PAINT GREEN (-7673 4850);
DISPLAY INVISIBLE (-7673 4850);
FORCEADD TAP..1
R 2
(-7675 4900);
FORCEPROP 3 LASTPIN (-7625 4900) SIG_NAME M_I_CPU1_SB_CA<5>
J 0
(-7615 4910);
DISPLAY 0.659574 (-7615 4910);
PAINT MONO (-7615 4910);
DISPLAY INVISIBLE (-7615 4910);
FORCEPROP 1 LASTPIN (-7625 4900) BN 5
J 2
(-7613 4908);
DISPLAY 0.489362 (-7613 4908);
PAINT GREEN (-7613 4908);
FORCEPROP 2 LAST CDS_LIB mstr_standard
J 0
(-7675 4900);
DISPLAY 0.723404 (-7675 4900);
PAINT MONO (-7675 4900);
DISPLAY INVISIBLE (-7675 4900);
FORCEPROP 1 LAST BODY_TYPE PLUMBING
J 2
(-7675 4950);
DISPLAY 0.872340 (-7675 4950);
PAINT GREEN (-7675 4950);
DISPLAY INVISIBLE (-7675 4950);
FORCEPROP 1 LAST HDL_TAP TRUE
J 2
(-8000 4775);
DISPLAY 0.872340 (-8000 4775);
DISPLAY INVISIBLE (-8000 4775);
FORCEPROP 1 LAST PATH I84
J 2
(-7673 4900);
DISPLAY 0.872340 (-7673 4900);
PAINT GREEN (-7673 4900);
DISPLAY INVISIBLE (-7673 4900);
FORCEADD TAP..1
R 2
(-7675 4950);
FORCEPROP 3 LASTPIN (-7625 4950) SIG_NAME M_I_CPU1_SB_CA<6>
J 0
(-7615 4960);
DISPLAY 0.659574 (-7615 4960);
PAINT MONO (-7615 4960);
DISPLAY INVISIBLE (-7615 4960);
FORCEPROP 1 LASTPIN (-7625 4950) BN 6
J 2
(-7613 4958);
DISPLAY 0.489362 (-7613 4958);
PAINT GREEN (-7613 4958);
FORCEPROP 2 LAST CDS_LIB mstr_standard
J 0
(-7675 4950);
DISPLAY 0.723404 (-7675 4950);
PAINT MONO (-7675 4950);
DISPLAY INVISIBLE (-7675 4950);
FORCEPROP 1 LAST BODY_TYPE PLUMBING
J 2
(-7675 5000);
DISPLAY 0.872340 (-7675 5000);
PAINT GREEN (-7675 5000);
DISPLAY INVISIBLE (-7675 5000);
FORCEPROP 1 LAST HDL_TAP TRUE
J 2
(-8000 4825);
DISPLAY 0.872340 (-8000 4825);
DISPLAY INVISIBLE (-8000 4825);
FORCEPROP 1 LAST PATH I85
J 2
(-7673 4950);
DISPLAY 0.872340 (-7673 4950);
PAINT GREEN (-7673 4950);
DISPLAY INVISIBLE (-7673 4950);
FORCEADD TAP..1
R 2
(-7675 5050);
FORCEPROP 3 LASTPIN (-7625 5050) SIG_NAME M_I_CPU1_SA_CA<0>
J 0
(-7615 5060);
DISPLAY 0.659574 (-7615 5060);
PAINT MONO (-7615 5060);
DISPLAY INVISIBLE (-7615 5060);
FORCEPROP 1 LASTPIN (-7625 5050) BN 0
J 2
(-7613 5058);
DISPLAY 0.489362 (-7613 5058);
PAINT GREEN (-7613 5058);
FORCEPROP 2 LAST CDS_LIB mstr_standard
J 0
(-7675 5050);
DISPLAY 0.723404 (-7675 5050);
PAINT MONO (-7675 5050);
DISPLAY INVISIBLE (-7675 5050);
FORCEPROP 1 LAST BODY_TYPE PLUMBING
J 2
(-7675 5100);
DISPLAY 0.872340 (-7675 5100);
PAINT GREEN (-7675 5100);
DISPLAY INVISIBLE (-7675 5100);
FORCEPROP 1 LAST HDL_TAP TRUE
J 2
(-8000 4925);
DISPLAY 0.872340 (-8000 4925);
DISPLAY INVISIBLE (-8000 4925);
FORCEPROP 1 LAST PATH I86
J 2
(-7673 5050);
DISPLAY 0.872340 (-7673 5050);
PAINT GREEN (-7673 5050);
DISPLAY INVISIBLE (-7673 5050);
FORCEADD TAP..1
R 2
(-7675 5100);
FORCEPROP 3 LASTPIN (-7625 5100) SIG_NAME M_I_CPU1_SA_CA<1>
J 0
(-7615 5110);
DISPLAY 0.659574 (-7615 5110);
PAINT MONO (-7615 5110);
DISPLAY INVISIBLE (-7615 5110);
FORCEPROP 1 LASTPIN (-7625 5100) BN 1
J 2
(-7613 5108);
DISPLAY 0.489362 (-7613 5108);
PAINT GREEN (-7613 5108);
FORCEPROP 2 LAST CDS_LIB mstr_standard
J 0
(-7675 5100);
DISPLAY 0.723404 (-7675 5100);
PAINT MONO (-7675 5100);
DISPLAY INVISIBLE (-7675 5100);
FORCEPROP 1 LAST BODY_TYPE PLUMBING
J 2
(-7675 5150);
DISPLAY 0.872340 (-7675 5150);
PAINT GREEN (-7675 5150);
DISPLAY INVISIBLE (-7675 5150);
FORCEPROP 1 LAST HDL_TAP TRUE
J 2
(-8000 4975);
DISPLAY 0.872340 (-8000 4975);
DISPLAY INVISIBLE (-8000 4975);
FORCEPROP 1 LAST PATH I87
J 2
(-7673 5100);
DISPLAY 0.872340 (-7673 5100);
PAINT GREEN (-7673 5100);
DISPLAY INVISIBLE (-7673 5100);
FORCEADD TAP..1
R 2
(-7675 5150);
FORCEPROP 3 LASTPIN (-7625 5150) SIG_NAME M_I_CPU1_SA_CA<2>
J 0
(-7615 5160);
DISPLAY 0.659574 (-7615 5160);
PAINT MONO (-7615 5160);
DISPLAY INVISIBLE (-7615 5160);
FORCEPROP 1 LASTPIN (-7625 5150) BN 2
J 2
(-7613 5158);
DISPLAY 0.489362 (-7613 5158);
PAINT GREEN (-7613 5158);
FORCEPROP 2 LAST CDS_LIB mstr_standard
J 0
(-7675 5150);
DISPLAY 0.723404 (-7675 5150);
PAINT MONO (-7675 5150);
DISPLAY INVISIBLE (-7675 5150);
FORCEPROP 1 LAST BODY_TYPE PLUMBING
J 2
(-7675 5200);
DISPLAY 0.872340 (-7675 5200);
PAINT GREEN (-7675 5200);
DISPLAY INVISIBLE (-7675 5200);
FORCEPROP 1 LAST HDL_TAP TRUE
J 2
(-8000 5025);
DISPLAY 0.872340 (-8000 5025);
DISPLAY INVISIBLE (-8000 5025);
FORCEPROP 1 LAST PATH I88
J 2
(-7673 5150);
DISPLAY 0.872340 (-7673 5150);
PAINT GREEN (-7673 5150);
DISPLAY INVISIBLE (-7673 5150);
FORCEADD TAP..1
R 2
(-7675 5200);
FORCEPROP 3 LASTPIN (-7625 5200) SIG_NAME M_I_CPU1_SA_CA<3>
J 0
(-7615 5210);
DISPLAY 0.659574 (-7615 5210);
PAINT MONO (-7615 5210);
DISPLAY INVISIBLE (-7615 5210);
FORCEPROP 1 LASTPIN (-7625 5200) BN 3
J 2
(-7613 5208);
DISPLAY 0.489362 (-7613 5208);
PAINT GREEN (-7613 5208);
FORCEPROP 2 LAST CDS_LIB mstr_standard
J 0
(-7675 5200);
DISPLAY 0.723404 (-7675 5200);
PAINT MONO (-7675 5200);
DISPLAY INVISIBLE (-7675 5200);
FORCEPROP 1 LAST BODY_TYPE PLUMBING
J 2
(-7675 5250);
DISPLAY 0.872340 (-7675 5250);
PAINT GREEN (-7675 5250);
DISPLAY INVISIBLE (-7675 5250);
FORCEPROP 1 LAST HDL_TAP TRUE
J 2
(-8000 5075);
DISPLAY 0.872340 (-8000 5075);
DISPLAY INVISIBLE (-8000 5075);
FORCEPROP 1 LAST PATH I89
J 2
(-7673 5200);
DISPLAY 0.872340 (-7673 5200);
PAINT GREEN (-7673 5200);
DISPLAY INVISIBLE (-7673 5200);
FORCEADD VCC_CORE..1
(-8450 3375);
FORCEPROP 3 LASTPIN (-8450 3325) SIG_NAME P3V3_AUX\g
J 0
(-8440 3335);
DISPLAY 0.659574 (-8440 3335);
PAINT MONO (-8440 3335);
DISPLAY INVISIBLE (-8440 3335);
FORCEPROP 1 LAST HDL_POWER P3V3_AUX
J 1
(-8450 3425);
DISPLAY 0.489362 (-8450 3425);
PAINT GREEN (-8450 3425);
FORCEPROP 2 LAST CDS_LIB mstr_symbols
J 0
(-8450 3375);
PAINT MONO (-8450 3375);
DISPLAY INVISIBLE (-8450 3375);
FORCEPROP 0 LAST VOLTAGE 3.3
J 0
(-8725 3525);
DISPLAY 1.021277 (-8725 3525);
PAINT SKYBLUE (-8725 3525);
DISPLAY INVISIBLE (-8725 3525);
FORCEPROP 2 LAST ROOM PVCCINFAON_CPU1_CTRL
J 0
(-8450 3475);
DISPLAY 0.808511 (-8450 3475);
PAINT RED (-8450 3475);
DISPLAY INVISIBLE (-8450 3475);
FORCEPROP 1 LAST PATH I9
J 0
(-8400 3400);
DISPLAY 0.872340 (-8400 3400);
PAINT AQUA (-8400 3400);
DISPLAY INVISIBLE (-8400 3400);
FORCEADD TAP..1
R 2
(-7675 5250);
FORCEPROP 3 LASTPIN (-7625 5250) SIG_NAME M_I_CPU1_SA_CA<4>
J 0
(-7615 5260);
DISPLAY 0.659574 (-7615 5260);
PAINT MONO (-7615 5260);
DISPLAY INVISIBLE (-7615 5260);
FORCEPROP 1 LASTPIN (-7625 5250) BN 4
J 2
(-7613 5258);
DISPLAY 0.489362 (-7613 5258);
PAINT GREEN (-7613 5258);
FORCEPROP 2 LAST CDS_LIB mstr_standard
J 0
(-7675 5250);
DISPLAY 0.723404 (-7675 5250);
PAINT MONO (-7675 5250);
DISPLAY INVISIBLE (-7675 5250);
FORCEPROP 1 LAST BODY_TYPE PLUMBING
J 2
(-7675 5300);
DISPLAY 0.872340 (-7675 5300);
PAINT GREEN (-7675 5300);
DISPLAY INVISIBLE (-7675 5300);
FORCEPROP 1 LAST HDL_TAP TRUE
J 2
(-8000 5125);
DISPLAY 0.872340 (-8000 5125);
DISPLAY INVISIBLE (-8000 5125);
FORCEPROP 1 LAST PATH I90
J 2
(-7673 5250);
DISPLAY 0.872340 (-7673 5250);
PAINT GREEN (-7673 5250);
DISPLAY INVISIBLE (-7673 5250);
FORCEADD TAP..1
R 2
(-7675 5300);
FORCEPROP 3 LASTPIN (-7625 5300) SIG_NAME M_I_CPU1_SA_CA<5>
J 0
(-7615 5310);
DISPLAY 0.659574 (-7615 5310);
PAINT MONO (-7615 5310);
DISPLAY INVISIBLE (-7615 5310);
FORCEPROP 1 LASTPIN (-7625 5300) BN 5
J 2
(-7613 5308);
DISPLAY 0.489362 (-7613 5308);
PAINT GREEN (-7613 5308);
FORCEPROP 2 LAST CDS_LIB mstr_standard
J 0
(-7675 5300);
DISPLAY 0.723404 (-7675 5300);
PAINT MONO (-7675 5300);
DISPLAY INVISIBLE (-7675 5300);
FORCEPROP 1 LAST BODY_TYPE PLUMBING
J 2
(-7675 5350);
DISPLAY 0.872340 (-7675 5350);
PAINT GREEN (-7675 5350);
DISPLAY INVISIBLE (-7675 5350);
FORCEPROP 1 LAST HDL_TAP TRUE
J 2
(-8000 5175);
DISPLAY 0.872340 (-8000 5175);
DISPLAY INVISIBLE (-8000 5175);
FORCEPROP 1 LAST PATH I91
J 2
(-7673 5300);
DISPLAY 0.872340 (-7673 5300);
PAINT GREEN (-7673 5300);
DISPLAY INVISIBLE (-7673 5300);
FORCEADD TAP..1
R 2
(-7675 5350);
FORCEPROP 3 LASTPIN (-7625 5350) SIG_NAME M_I_CPU1_SA_CA<6>
J 0
(-7615 5360);
DISPLAY 0.659574 (-7615 5360);
PAINT MONO (-7615 5360);
DISPLAY INVISIBLE (-7615 5360);
FORCEPROP 1 LASTPIN (-7625 5350) BN 6
J 2
(-7613 5358);
DISPLAY 0.489362 (-7613 5358);
PAINT GREEN (-7613 5358);
FORCEPROP 2 LAST CDS_LIB mstr_standard
J 0
(-7675 5350);
DISPLAY 0.723404 (-7675 5350);
PAINT MONO (-7675 5350);
DISPLAY INVISIBLE (-7675 5350);
FORCEPROP 1 LAST BODY_TYPE PLUMBING
J 2
(-7675 5400);
DISPLAY 0.872340 (-7675 5400);
PAINT GREEN (-7675 5400);
DISPLAY INVISIBLE (-7675 5400);
FORCEPROP 1 LAST HDL_TAP TRUE
J 2
(-8000 5225);
DISPLAY 0.872340 (-8000 5225);
DISPLAY INVISIBLE (-8000 5225);
FORCEPROP 1 LAST PATH I92
J 2
(-7673 5350);
DISPLAY 0.872340 (-7673 5350);
PAINT GREEN (-7673 5350);
DISPLAY INVISIBLE (-7673 5350);
FORCEADD TAP..1
(-5975 3800);
FORCEPROP 3 LASTPIN (-6025 3800) SIG_NAME M_I_CPU1_SA_DQ<0>
J 0
(-6015 3810);
DISPLAY 0.659574 (-6015 3810);
PAINT MONO (-6015 3810);
DISPLAY INVISIBLE (-6015 3810);
FORCEPROP 1 LASTPIN (-6025 3800) BN 0
J 0
(-6037 3808);
DISPLAY 0.489362 (-6037 3808);
PAINT GREEN (-6037 3808);
FORCEPROP 2 LAST CDS_LIB mstr_standard
J 0
(-5975 3800);
DISPLAY 0.723404 (-5975 3800);
PAINT MONO (-5975 3800);
DISPLAY INVISIBLE (-5975 3800);
FORCEPROP 1 LAST BODY_TYPE PLUMBING
J 0
(-5975 3850);
DISPLAY 0.872340 (-5975 3850);
PAINT GREEN (-5975 3850);
DISPLAY INVISIBLE (-5975 3850);
FORCEPROP 1 LAST HDL_TAP TRUE
J 0
(-5650 3675);
DISPLAY 0.872340 (-5650 3675);
DISPLAY INVISIBLE (-5650 3675);
FORCEPROP 1 LAST PATH I93
J 0
(-5977 3800);
DISPLAY 0.872340 (-5977 3800);
PAINT GREEN (-5977 3800);
DISPLAY INVISIBLE (-5977 3800);
FORCEADD TAP..1
(-5975 3900);
FORCEPROP 3 LASTPIN (-6025 3900) SIG_NAME M_I_CPU1_SA_DQ<2>
J 0
(-6015 3910);
DISPLAY 0.659574 (-6015 3910);
PAINT MONO (-6015 3910);
DISPLAY INVISIBLE (-6015 3910);
FORCEPROP 1 LASTPIN (-6025 3900) BN 2
J 0
(-6037 3908);
DISPLAY 0.489362 (-6037 3908);
PAINT GREEN (-6037 3908);
FORCEPROP 2 LAST CDS_LIB mstr_standard
J 0
(-5975 3900);
DISPLAY 0.723404 (-5975 3900);
PAINT MONO (-5975 3900);
DISPLAY INVISIBLE (-5975 3900);
FORCEPROP 1 LAST BODY_TYPE PLUMBING
J 0
(-5975 3950);
DISPLAY 0.872340 (-5975 3950);
PAINT GREEN (-5975 3950);
DISPLAY INVISIBLE (-5975 3950);
FORCEPROP 1 LAST HDL_TAP TRUE
J 0
(-5650 3775);
DISPLAY 0.872340 (-5650 3775);
DISPLAY INVISIBLE (-5650 3775);
FORCEPROP 1 LAST PATH I94
J 0
(-5977 3900);
DISPLAY 0.872340 (-5977 3900);
PAINT GREEN (-5977 3900);
DISPLAY INVISIBLE (-5977 3900);
FORCEADD TAP..1
(-5975 3850);
FORCEPROP 3 LASTPIN (-6025 3850) SIG_NAME M_I_CPU1_SA_DQ<1>
J 0
(-6015 3860);
DISPLAY 0.659574 (-6015 3860);
PAINT MONO (-6015 3860);
DISPLAY INVISIBLE (-6015 3860);
FORCEPROP 1 LASTPIN (-6025 3850) BN 1
J 0
(-6037 3858);
DISPLAY 0.489362 (-6037 3858);
PAINT GREEN (-6037 3858);
FORCEPROP 2 LAST CDS_LIB mstr_standard
J 0
(-5975 3850);
DISPLAY 0.723404 (-5975 3850);
PAINT MONO (-5975 3850);
DISPLAY INVISIBLE (-5975 3850);
FORCEPROP 1 LAST BODY_TYPE PLUMBING
J 0
(-5975 3900);
DISPLAY 0.872340 (-5975 3900);
PAINT GREEN (-5975 3900);
DISPLAY INVISIBLE (-5975 3900);
FORCEPROP 1 LAST HDL_TAP TRUE
J 0
(-5650 3725);
DISPLAY 0.872340 (-5650 3725);
DISPLAY INVISIBLE (-5650 3725);
FORCEPROP 1 LAST PATH I95
J 0
(-5977 3850);
DISPLAY 0.872340 (-5977 3850);
PAINT GREEN (-5977 3850);
DISPLAY INVISIBLE (-5977 3850);
FORCEADD TAP..1
(-5975 3950);
FORCEPROP 3 LASTPIN (-6025 3950) SIG_NAME M_I_CPU1_SA_DQ<3>
J 0
(-6015 3960);
DISPLAY 0.659574 (-6015 3960);
PAINT MONO (-6015 3960);
DISPLAY INVISIBLE (-6015 3960);
FORCEPROP 1 LASTPIN (-6025 3950) BN 3
J 0
(-6037 3958);
DISPLAY 0.489362 (-6037 3958);
PAINT GREEN (-6037 3958);
FORCEPROP 2 LAST CDS_LIB mstr_standard
J 0
(-5975 3950);
DISPLAY 0.723404 (-5975 3950);
PAINT MONO (-5975 3950);
DISPLAY INVISIBLE (-5975 3950);
FORCEPROP 1 LAST BODY_TYPE PLUMBING
J 0
(-5975 4000);
DISPLAY 0.872340 (-5975 4000);
PAINT GREEN (-5975 4000);
DISPLAY INVISIBLE (-5975 4000);
FORCEPROP 1 LAST HDL_TAP TRUE
J 0
(-5650 3825);
DISPLAY 0.872340 (-5650 3825);
DISPLAY INVISIBLE (-5650 3825);
FORCEPROP 1 LAST PATH I96
J 0
(-5977 3950);
DISPLAY 0.872340 (-5977 3950);
PAINT GREEN (-5977 3950);
DISPLAY INVISIBLE (-5977 3950);
FORCEADD TAP..1
(-5975 4000);
FORCEPROP 3 LASTPIN (-6025 4000) SIG_NAME M_I_CPU1_SA_DQ<4>
J 0
(-6015 4010);
DISPLAY 0.659574 (-6015 4010);
PAINT MONO (-6015 4010);
DISPLAY INVISIBLE (-6015 4010);
FORCEPROP 1 LASTPIN (-6025 4000) BN 4
J 0
(-6037 4008);
DISPLAY 0.489362 (-6037 4008);
PAINT GREEN (-6037 4008);
FORCEPROP 2 LAST CDS_LIB mstr_standard
J 0
(-5975 4000);
DISPLAY 0.723404 (-5975 4000);
PAINT MONO (-5975 4000);
DISPLAY INVISIBLE (-5975 4000);
FORCEPROP 1 LAST BODY_TYPE PLUMBING
J 0
(-5975 4050);
DISPLAY 0.872340 (-5975 4050);
PAINT GREEN (-5975 4050);
DISPLAY INVISIBLE (-5975 4050);
FORCEPROP 1 LAST HDL_TAP TRUE
J 0
(-5650 3875);
DISPLAY 0.872340 (-5650 3875);
DISPLAY INVISIBLE (-5650 3875);
FORCEPROP 1 LAST PATH I97
J 0
(-5977 4000);
DISPLAY 0.872340 (-5977 4000);
PAINT GREEN (-5977 4000);
DISPLAY INVISIBLE (-5977 4000);
FORCEADD TAP..1
(-5975 4050);
FORCEPROP 3 LASTPIN (-6025 4050) SIG_NAME M_I_CPU1_SA_DQ<5>
J 0
(-6015 4060);
DISPLAY 0.659574 (-6015 4060);
PAINT MONO (-6015 4060);
DISPLAY INVISIBLE (-6015 4060);
FORCEPROP 1 LASTPIN (-6025 4050) BN 5
J 0
(-6037 4058);
DISPLAY 0.489362 (-6037 4058);
PAINT GREEN (-6037 4058);
FORCEPROP 2 LAST CDS_LIB mstr_standard
J 0
(-5975 4050);
DISPLAY 0.723404 (-5975 4050);
PAINT MONO (-5975 4050);
DISPLAY INVISIBLE (-5975 4050);
FORCEPROP 1 LAST BODY_TYPE PLUMBING
J 0
(-5975 4100);
DISPLAY 0.872340 (-5975 4100);
PAINT GREEN (-5975 4100);
DISPLAY INVISIBLE (-5975 4100);
FORCEPROP 1 LAST HDL_TAP TRUE
J 0
(-5650 3925);
DISPLAY 0.872340 (-5650 3925);
DISPLAY INVISIBLE (-5650 3925);
FORCEPROP 1 LAST PATH I98
J 0
(-5977 4050);
DISPLAY 0.872340 (-5977 4050);
PAINT GREEN (-5977 4050);
DISPLAY INVISIBLE (-5977 4050);
FORCEADD TAP..1
(-5975 4100);
FORCEPROP 3 LASTPIN (-6025 4100) SIG_NAME M_I_CPU1_SA_DQ<6>
J 0
(-6015 4110);
DISPLAY 0.659574 (-6015 4110);
PAINT MONO (-6015 4110);
DISPLAY INVISIBLE (-6015 4110);
FORCEPROP 1 LASTPIN (-6025 4100) BN 6
J 0
(-6037 4108);
DISPLAY 0.489362 (-6037 4108);
PAINT GREEN (-6037 4108);
FORCEPROP 2 LAST CDS_LIB mstr_standard
J 0
(-5975 4100);
DISPLAY 0.723404 (-5975 4100);
PAINT MONO (-5975 4100);
DISPLAY INVISIBLE (-5975 4100);
FORCEPROP 1 LAST BODY_TYPE PLUMBING
J 0
(-5975 4150);
DISPLAY 0.872340 (-5975 4150);
PAINT GREEN (-5975 4150);
DISPLAY INVISIBLE (-5975 4150);
FORCEPROP 1 LAST HDL_TAP TRUE
J 0
(-5650 3975);
DISPLAY 0.872340 (-5650 3975);
DISPLAY INVISIBLE (-5650 3975);
FORCEPROP 1 LAST PATH I99
J 0
(-5977 4100);
DISPLAY 0.872340 (-5977 4100);
PAINT GREEN (-5977 4100);
DISPLAY INVISIBLE (-5977 4100);
FORCEADD QUANTA_TITLE_BLOCK_C..1
(0 0);
FORCEPROP 0 LAST CDS_CON_LAST_MODIFIED Thu Sep 14 16:12:12 2023
J 0
(-1885 15);
DISPLAY INVISIBLE (-1885 15);
FORCEPROP 1 LAST CUSTOM_TXT_CDS <CON_LAST_MODIFIED>
J 0
(-1885 15);
DISPLAY 0.978723 (-1885 15);
FORCEPROP 2 LAST CUSTOM_TXT_CDS <XR_PAGE_TITLE>
J 0
(-7890 5250);
DISPLAY 0.638298 (-7890 5250);
PAINT PINK (-7890 5250);
DISPLAY INVISIBLE (-7890 5250);
FORCEPROP 1 LAST CUSTOM_TXT_CDS <NAME_2>
J 0
(-3175 50);
FORCEPROP 1 LAST CUSTOM_TXT_CDS <NAME_1>
J 0
(-3175 175);
FORCEPROP 1 LAST CUSTOM_TXT_CDS <Q_NUMBER>
J 0
(-1403 103);
DISPLAY 1.212766 (-1403 103);
FORCEPROP 1 LAST CUSTOM_TXT_CDS <Q_PROJ>
J 0
(-2382 102);
DISPLAY 1.212766 (-2382 102);
FORCEPROP 1 LAST CUSTOM_TXT_CDS <Q_REV>
J 0
(-184 103);
DISPLAY 1.212766 (-184 103);
FORCEPROP 1 LAST CUSTOM_TXT_CDS <CON_PAGE_NUM> OF <CON_TOTAL_PAGES>
J 0
(-446 18);
DISPLAY 0.978723 (-446 18);
FORCEPROP 1 LAST Q_TITLE DDR5 - CPU1 CHI
J 0
(-9366 26);
DISPLAY 2.446809 (-9366 26);
PAINT GREEN (-9366 26);
FORCEPROP 2 LAST PAGE_BORDER TRUE
J 0
(-7890 5250);
DISPLAY 0.638298 (-7890 5250);
PAINT PINK (-7890 5250);
DISPLAY INVISIBLE (-7890 5250);
FORCEPROP 1 LAST CDS_LMAN_SYM_OUTLINE -9475,6775,100,-125
J 0
(0 0);
DISPLAY 0.468085 (0 0);
PAINT GREEN (0 0);
DISPLAY INVISIBLE (0 0);
FORCEPROP 2 LAST CDS_LIB pure_quanta
J 0
(0 0);
DISPLAY INVISIBLE (0 0);
FORCEPROP 2 LAST CDS_XR_PAGE_TITLE CR-106 : @T6G_MB_LIB.T6G(SCH_1):PAGE106
J 0
(-7890 5250);
DISPLAY 0.638298 (-7890 5250);
PAINT PINK (-7890 5250);
DISPLAY INVISIBLE (-7890 5250);
FORCEPROP 1 LAST Q_DEPT BU9
J 1
(-3763 49);
DISPLAY 1.957447 (-3763 49);
PAINT GREEN (-3763 49);
DISPLAY INVISIBLE (-3763 49);
FORCEPROP 1 LAST COMMENT_BODY TRUE
J 0
(12 -13);
DISPLAY 0.978723 (12 -13);
PAINT GREEN (12 -13);
DISPLAY INVISIBLE (12 -13);
FORCEADD DNS..2
(-8325 2250);
PAINT RED (-8325 2250);
FORCEPROP 2 LAST CDS_LIB mstr_misc
J 0
(-8325 2250);
DISPLAY INVISIBLE (-8325 2250);
FORCEPROP 1 LAST COMMENT_BODY TRUE
R 1
J 0
(-8250 2025);
DISPLAY 0.872340 (-8250 2025);
PAINT PEACH (-8250 2025);
DISPLAY INVISIBLE (-8250 2025);
WIRE 17 -1 (-7725 3875)(-7725 3825);
WIRE 17 -1 (-7725 3875)(-7725 3925);
WIRE 17 -1 (-7725 3775)(-7725 3825);
WIRE 17 -1 (-7725 3725)(-7725 3775);
WIRE 17 -1 (-7725 3975)(-7725 3925);
WIRE 17 -1 (-7725 3975)(-7725 4000);
WIRE 17 -1 (-7725 3675)(-7725 3725);
WIRE 17 -1 (-7725 3625)(-7725 3675);
WIRE 17 -1 (-7725 4000)(-8225 4000);
FORCEPROP 2 LAST SIG_NAME M_I_CPU1_SA_CB<7:0>
J 0
(-8175 4010);
DISPLAY 0.489362 (-8175 4010);
WIRE 17 -1 (-7725 3525)(-7725 3550);
WIRE 17 -1 (-7725 3525)(-7725 3475);
WIRE 17 -1 (-7725 3550)(-8225 3550);
FORCEPROP 2 LAST SIG_NAME M_I_CPU1_SB_CB<7:0>
J 0
(-8175 3560);
DISPLAY 0.489362 (-8175 3560);
WIRE 17 -1 (-7725 5075)(-7725 5125);
WIRE 17 -1 (-7725 5125)(-7725 5175);
WIRE 17 -1 (-7725 5175)(-7725 5225);
WIRE 17 -1 (-7725 5225)(-7725 5275);
WIRE 17 -1 (-7725 5275)(-7725 5325);
WIRE 17 -1 (-7725 5325)(-7725 5375);
WIRE 17 -1 (-7725 5375)(-7725 5400);
WIRE 17 -1 (-7725 5400)(-8225 5400);
FORCEPROP 2 LAST SIG_NAME M_I_CPU1_SA_CA<6:0>
J 0
(-8210 5410);
DISPLAY 0.489362 (-8210 5410);
WIRE 17 -1 (-7725 4675)(-7725 4725);
WIRE 17 -1 (-7725 4725)(-7725 4775);
WIRE 17 -1 (-7725 4775)(-7725 4825);
WIRE 17 -1 (-7725 4825)(-7725 4875);
WIRE 17 -1 (-7725 4875)(-7725 4925);
WIRE 17 -1 (-7725 4925)(-7725 4975);
WIRE 17 -1 (-7725 4975)(-7725 5000);
WIRE 17 -1 (-7725 5000)(-8225 5000);
FORCEPROP 2 LAST SIG_NAME M_I_CPU1_SB_CA<6:0>
J 0
(-8210 5010);
DISPLAY 0.489362 (-8210 5010);
WIRE 17 -1 (-7725 3425)(-7725 3375);
WIRE 17 -1 (-7725 3425)(-7725 3475);
WIRE 17 -1 (-7725 3325)(-7725 3375);
WIRE 17 -1 (-7725 3275)(-7725 3325);
WIRE 17 -1 (-7725 3225)(-7725 3275);
WIRE 17 -1 (-7725 3175)(-7725 3225);
WIRE 17 -1 (-5925 5375)(-5925 5325);
WIRE 17 -1 (-5925 5400)(-5925 5375);
WIRE 17 -1 (-5925 5325)(-5925 5275);
WIRE 17 -1 (-5925 5275)(-5925 5225);
WIRE 17 -1 (-5925 5400)(-5325 5400);
FORCEPROP 2 LAST SIG_NAME M_I_CPU1_SA_DQ<31:0>
J 0
(-5860 5410);
DISPLAY 0.489362 (-5860 5410);
WIRE 17 -1 (-5925 5225)(-5925 5175);
WIRE 17 -1 (-5925 5175)(-5925 5125);
WIRE 17 -1 (-5925 5125)(-5925 5075);
WIRE 17 -1 (-5925 5075)(-5925 5025);
WIRE 17 -1 (-5925 5025)(-5925 4975);
WIRE 17 -1 (-5925 4975)(-5925 4925);
WIRE 17 -1 (-5925 4925)(-5925 4875);
WIRE 17 -1 (-5925 4875)(-5925 4825);
WIRE 17 -1 (-5925 4825)(-5925 4775);
WIRE 17 -1 (-5925 4775)(-5925 4725);
WIRE 17 -1 (-5925 4725)(-5925 4675);
WIRE 17 -1 (-5925 4675)(-5925 4625);
WIRE 17 -1 (-5925 4575)(-5925 4625);
WIRE 17 -1 (-5925 4525)(-5925 4575);
WIRE 17 -1 (-5925 4475)(-5925 4525);
WIRE 17 -1 (-5925 4425)(-5925 4475);
WIRE 17 -1 (-5925 4425)(-5925 4375);
WIRE 17 -1 (-5925 4375)(-5925 4325);
WIRE 17 -1 (-5925 4325)(-5925 4275);
WIRE 17 -1 (-5925 4275)(-5925 4225);
WIRE 17 -1 (-5925 4225)(-5925 4175);
WIRE 17 -1 (-5925 4175)(-5925 4125);
WIRE 17 -1 (-5925 4125)(-5925 4075);
WIRE 17 -1 (-5925 4075)(-5925 4025);
WIRE 17 -1 (-5925 3975)(-5925 4025);
WIRE 17 -1 (-5925 3925)(-5925 3975);
WIRE 17 -1 (-5925 3875)(-5925 3925);
WIRE 17 -1 (-5925 3825)(-5925 3875);
WIRE 17 -1 (-5925 3750)(-5925 3725);
WIRE 17 -1 (-5925 3750)(-5325 3750);
FORCEPROP 2 LAST SIG_NAME M_I_CPU1_SB_DQ<31:0>
J 0
(-5860 3760);
DISPLAY 0.489362 (-5860 3760);
WIRE 17 -1 (-5925 3725)(-5925 3675);
WIRE 17 -1 (-5925 3675)(-5925 3625);
WIRE 17 -1 (-5925 3625)(-5925 3575);
WIRE 17 -1 (-5925 3575)(-5925 3525);
WIRE 17 -1 (-5925 3525)(-5925 3475);
WIRE 17 -1 (-5925 3475)(-5925 3425);
WIRE 17 -1 (-5925 3425)(-5925 3375);
WIRE 17 -1 (-5925 3375)(-5925 3325);
WIRE 17 -1 (-5925 3325)(-5925 3275);
WIRE 17 -1 (-5925 3275)(-5925 3225);
WIRE 17 -1 (-5925 3225)(-5925 3175);
WIRE 17 -1 (-5925 3175)(-5925 3125);
WIRE 17 -1 (-5925 3125)(-5925 3075);
WIRE 17 -1 (-5925 3075)(-5925 3025);
WIRE 17 -1 (-5925 3025)(-5925 2975);
WIRE 17 -1 (-5925 2925)(-5925 2975);
WIRE 17 -1 (-5925 2875)(-5925 2925);
WIRE 17 -1 (-5925 2825)(-5925 2875);
WIRE 17 -1 (-5925 2775)(-5925 2825);
WIRE 17 -1 (-5925 2775)(-5925 2725);
WIRE 17 -1 (-5925 2725)(-5925 2675);
WIRE 17 -1 (-5925 2675)(-5925 2625);
WIRE 17 -1 (-5925 2625)(-5925 2575);
WIRE 17 -1 (-5925 2575)(-5925 2525);
WIRE 17 -1 (-5925 2525)(-5925 2475);
WIRE 17 -1 (-5925 2475)(-5925 2425);
WIRE 17 -1 (-5925 2425)(-5925 2375);
WIRE 17 -1 (-5925 2325)(-5925 2375);
WIRE 17 -1 (-5925 2275)(-5925 2325);
WIRE 17 -1 (-5925 2225)(-5925 2275);
WIRE 17 -1 (-5925 2175)(-5925 2225);
WIRE 17 -1 (-3200 4275)(-3200 4175);
WIRE 17 -1 (-3200 4375)(-3200 4275);
WIRE 17 -1 (-3200 4175)(-3200 4075);
WIRE 17 -1 (-3200 4075)(-3200 3975);
WIRE 17 -1 (-3200 4400)(-3200 4375);
WIRE 17 -1 (-3200 4400)(-2500 4400);
FORCEPROP 2 LAST SIG_NAME M_I_CPU1_SA_DQS_DN<9:0>
J 0
(-3135 4410);
DISPLAY 0.489362 (-3135 4410);
WIRE 17 -1 (-3400 4225)(-3400 4125);
WIRE 17 -1 (-3400 4325)(-3400 4225);
WIRE 17 -1 (-3400 4125)(-3400 4025);
WIRE 17 -1 (-3400 3925)(-3400 4025);
WIRE 17 -1 (-3400 4425)(-3400 4325);
WIRE 17 -1 (-3400 4450)(-3400 4425);
WIRE 17 -1 (-3400 3825)(-3400 3925);
WIRE 17 -1 (-3400 3725)(-3400 3825);
WIRE 17 -1 (-3400 4450)(-2500 4450);
FORCEPROP 2 LAST SIG_NAME M_I_CPU1_SA_DQS_DP<9:0>
J 0
(-3135 4460);
DISPLAY 0.489362 (-3135 4460);
WIRE 17 -1 (-3400 3375)(-3400 3275);
WIRE 17 -1 (-3400 3400)(-3400 3375);
WIRE 17 -1 (-3400 3275)(-3400 3175);
WIRE 17 -1 (-3400 3175)(-3400 3075);
WIRE 17 -1 (-3400 3400)(-2500 3400);
FORCEPROP 2 LAST SIG_NAME M_I_CPU1_SB_DQS_DP<9:0>
J 0
(-3135 3410);
DISPLAY 0.489362 (-3135 3410);
WIRE 17 -1 (-3200 3325)(-3200 3225);
WIRE 17 -1 (-3200 3350)(-3200 3325);
WIRE 17 -1 (-3200 3225)(-3200 3125);
WIRE 17 -1 (-3200 3125)(-3200 3025);
WIRE 17 -1 (-3200 3350)(-2500 3350);
FORCEPROP 2 LAST SIG_NAME M_I_CPU1_SB_DQS_DN<9:0>
J 0
(-3135 3360);
DISPLAY 0.489362 (-3135 3360);
WIRE 17 -1 (-3400 3075)(-3400 2975);
WIRE 17 -1 (-3200 3575)(-3200 3475);
WIRE 17 -1 (-3200 3675)(-3200 3575);
WIRE 17 -1 (-3200 3675)(-3200 3775);
WIRE 17 -1 (-3200 3775)(-3200 3875);
WIRE 17 -1 (-3200 3875)(-3200 3975);
WIRE 17 -1 (-3400 3625)(-3400 3525);
WIRE 17 -1 (-3400 3725)(-3400 3625);
WIRE 17 -1 (-3200 2525)(-3200 2425);
WIRE 17 -1 (-3200 2625)(-3200 2525);
WIRE 17 -1 (-3200 2625)(-3200 2725);
WIRE 17 -1 (-3200 2725)(-3200 2825);
WIRE 17 -1 (-3200 2825)(-3200 2925);
WIRE 17 -1 (-3200 3025)(-3200 2925);
WIRE 17 -1 (-3400 2575)(-3400 2475);
WIRE 17 -1 (-3400 2675)(-3400 2575);
WIRE 17 -1 (-3400 2675)(-3400 2775);
WIRE 17 -1 (-3400 2775)(-3400 2875);
WIRE 17 -1 (-3400 2875)(-3400 2975);
WIRE 16 -1 (-6375 975)(-6375 1050);
WIRE 16 -1 (-8550 3000)(-8550 3075);
WIRE 16 -1 (-8350 2350)(-8350 2375);
WIRE 16 -1 (-7425 3250)(-7625 3250);
WIRE 16 -1 (-7425 3000)(-8075 3000);
FORCEPROP 2 LAST SIG_NAME M_I_CPU1_ALERT_N
J 0
(-8060 3010);
DISPLAY 0.489362 (-8060 3010);
WIRE 16 -1 (-1825 2050)(-2125 2050);
WIRE 16 -1 (-2125 2100)(-2125 2050);
WIRE 16 -1 (-2125 2050)(-2125 2000);
WIRE 16 -1 (-1825 2000)(-2125 2000);
WIRE 16 -1 (-2125 2000)(-2125 1875);
WIRE 16 -1 (-1825 2100)(-2125 2100);
WIRE 16 -1 (-2125 2150)(-2125 2100);
WIRE 16 -1 (-1825 2150)(-2125 2150);
WIRE 16 -1 (-2125 2200)(-2125 2150);
WIRE 16 -1 (-1825 2200)(-2125 2200);
WIRE 16 -1 (-2125 2250)(-2125 2200);
WIRE 16 -1 (-1825 2250)(-2125 2250);
WIRE 16 -1 (-2125 2300)(-2125 2250);
WIRE 16 -1 (-1825 2300)(-2125 2300);
WIRE 16 -1 (-2125 2350)(-2125 2300);
WIRE 16 -1 (-1825 2350)(-2125 2350);
WIRE 16 -1 (-2125 2400)(-2125 2350);
WIRE 16 -1 (-1825 2400)(-2125 2400);
WIRE 16 -1 (-2125 2450)(-2125 2400);
WIRE 16 -1 (-1825 2450)(-2125 2450);
WIRE 16 -1 (-2125 2500)(-2125 2450);
WIRE 16 -1 (-1825 2500)(-2125 2500);
WIRE 16 -1 (-2125 2550)(-2125 2500);
WIRE 16 -1 (-1825 2550)(-2125 2550);
WIRE 16 -1 (-2125 2600)(-2125 2550);
WIRE 16 -1 (-1825 2600)(-2125 2600);
WIRE 16 -1 (-2125 2650)(-2125 2600);
WIRE 16 -1 (-1825 2650)(-2125 2650);
WIRE 16 -1 (-2125 2700)(-2125 2650);
WIRE 16 -1 (-1825 2700)(-2125 2700);
WIRE 16 -1 (-2125 2750)(-2125 2700);
WIRE 16 -1 (-1825 2750)(-2125 2750);
WIRE 16 -1 (-2125 2800)(-2125 2750);
WIRE 16 -1 (-1825 2800)(-2125 2800);
WIRE 16 -1 (-2125 2850)(-2125 2800);
WIRE 16 -1 (-1825 2850)(-2125 2850);
WIRE 16 -1 (-2125 2900)(-2125 2850);
WIRE 16 -1 (-1825 2900)(-2125 2900);
WIRE 16 -1 (-2125 2950)(-2125 2900);
WIRE 16 -1 (-1825 2950)(-2125 2950);
WIRE 16 -1 (-2125 3000)(-2125 2950);
WIRE 16 -1 (-1825 3000)(-2125 3000);
WIRE 16 -1 (-2125 3050)(-2125 3000);
WIRE 16 -1 (-1825 3050)(-2125 3050);
WIRE 16 -1 (-2125 3100)(-2125 3050);
WIRE 16 -1 (-1825 3100)(-2125 3100);
WIRE 16 -1 (-2125 3150)(-2125 3100);
WIRE 16 -1 (-1825 3150)(-2125 3150);
WIRE 16 -1 (-2125 3200)(-2125 3150);
WIRE 16 -1 (-1825 3200)(-2125 3200);
WIRE 16 -1 (-2125 3250)(-2125 3200);
WIRE 16 -1 (-1825 3250)(-2125 3250);
WIRE 16 -1 (-2125 3300)(-2125 3250);
WIRE 16 -1 (-1825 3300)(-2125 3300);
WIRE 16 -1 (-2125 3350)(-2125 3300);
WIRE 16 -1 (-1825 3350)(-2125 3350);
WIRE 16 -1 (-2125 3400)(-2125 3350);
WIRE 16 -1 (-1825 3400)(-2125 3400);
WIRE 16 -1 (-2125 3450)(-2125 3400);
WIRE 16 -1 (-1825 3450)(-2125 3450);
WIRE 16 -1 (-2125 3500)(-2125 3450);
WIRE 16 -1 (-1825 3500)(-2125 3500);
WIRE 16 -1 (-2125 3550)(-2125 3500);
WIRE 16 -1 (-1825 3550)(-2125 3550);
WIRE 16 -1 (-2125 3600)(-2125 3550);
WIRE 16 -1 (-1825 3600)(-2125 3600);
WIRE 16 -1 (-2125 3650)(-2125 3600);
WIRE 16 -1 (-1825 3650)(-2125 3650);
WIRE 16 -1 (-2125 3700)(-2125 3650);
WIRE 16 -1 (-1825 3700)(-2125 3700);
WIRE 16 -1 (-2125 3750)(-2125 3700);
WIRE 16 -1 (-1825 3750)(-2125 3750);
WIRE 16 -1 (-2125 3800)(-2125 3750);
WIRE 16 -1 (-1825 3800)(-2125 3800);
WIRE 16 -1 (-2125 3850)(-2125 3800);
WIRE 16 -1 (-1825 3850)(-2125 3850);
WIRE 16 -1 (-2125 3900)(-2125 3850);
WIRE 16 -1 (-1825 3900)(-2125 3900);
WIRE 16 -1 (-2125 3950)(-2125 3900);
WIRE 16 -1 (-1825 3950)(-2125 3950);
WIRE 16 -1 (-2125 4000)(-2125 3950);
WIRE 16 -1 (-1825 4000)(-2125 4000);
WIRE 16 -1 (-2125 4050)(-2125 4000);
WIRE 16 -1 (-2125 4100)(-2125 4050);
WIRE 16 -1 (-1825 4050)(-2125 4050);
WIRE 16 -1 (-1825 4100)(-2125 4100);
WIRE 16 -1 (-2125 4150)(-2125 4100);
WIRE 16 -1 (-1825 4150)(-2125 4150);
WIRE 16 -1 (-2125 4200)(-2125 4150);
WIRE 16 -1 (-1825 4200)(-2125 4200);
WIRE 16 -1 (-2125 4250)(-2125 4200);
WIRE 16 -1 (-1825 4250)(-2125 4250);
WIRE 16 -1 (-2125 4300)(-2125 4250);
WIRE 16 -1 (-1825 4300)(-2125 4300);
WIRE 16 -1 (-2125 4350)(-2125 4300);
WIRE 16 -1 (-1825 4350)(-2125 4350);
WIRE 16 -1 (-2125 4400)(-2125 4350);
WIRE 16 -1 (-1825 4400)(-2125 4400);
WIRE 16 -1 (-2125 4450)(-2125 4400);
WIRE 16 -1 (-1825 4450)(-2125 4450);
WIRE 16 -1 (-2125 4500)(-2125 4450);
WIRE 16 -1 (-1825 4500)(-2125 4500);
WIRE 16 -1 (-2125 4550)(-2125 4500);
WIRE 16 -1 (-1825 4550)(-2125 4550);
WIRE 16 -1 (-2125 4600)(-2125 4550);
WIRE 16 -1 (-1825 4600)(-2125 4600);
WIRE 16 -1 (-2125 4650)(-2125 4600);
WIRE 16 -1 (-1825 4650)(-2125 4650);
WIRE 16 -1 (-2125 4700)(-2125 4650);
WIRE 16 -1 (-1825 4700)(-2125 4700);
WIRE 16 -1 (-2125 4750)(-2125 4700);
WIRE 16 -1 (-1825 4750)(-2125 4750);
WIRE 16 -1 (-2125 4800)(-2125 4750);
WIRE 16 -1 (-1825 4800)(-2125 4800);
WIRE 16 -1 (-2125 4850)(-2125 4800);
WIRE 16 -1 (-1825 4850)(-2125 4850);
WIRE 16 -1 (-2125 4900)(-2125 4850);
WIRE 16 -1 (-1825 4900)(-2125 4900);
WIRE 16 -1 (-2125 4950)(-2125 4900);
WIRE 16 -1 (-1825 4950)(-2125 4950);
WIRE 16 -1 (-2125 5000)(-2125 4950);
WIRE 16 -1 (-1825 5000)(-2125 5000);
WIRE 16 -1 (-2125 5050)(-2125 5000);
WIRE 16 -1 (-1825 5050)(-2125 5050);
WIRE 16 -1 (-2125 5100)(-2125 5050);
WIRE 16 -1 (-1825 5100)(-2125 5100);
WIRE 16 -1 (-325 2100)(-325 2000);
WIRE 16 -1 (-325 2150)(-325 2100);
WIRE 16 -1 (-325 2100)(-625 2100);
WIRE 16 -1 (-325 2000)(-325 1950);
WIRE 16 -1 (-325 2000)(-625 2000);
WIRE 16 -1 (-325 1950)(-325 1900);
WIRE 16 -1 (-325 1950)(-625 1950);
WIRE 16 -1 (-325 2200)(-325 2150);
WIRE 16 -1 (-325 2150)(-625 2150);
WIRE 16 -1 (-325 2250)(-325 2200);
WIRE 16 -1 (-325 2200)(-625 2200);
WIRE 16 -1 (-325 1900)(-325 1650);
WIRE 16 -1 (-325 1900)(-625 1900);
WIRE 16 -1 (-325 2300)(-325 2250);
WIRE 16 -1 (-325 2250)(-625 2250);
WIRE 16 -1 (-325 2350)(-325 2300);
WIRE 16 -1 (-325 2300)(-625 2300);
WIRE 16 -1 (-325 2400)(-325 2350);
WIRE 16 -1 (-325 2350)(-625 2350);
WIRE 16 -1 (-325 2450)(-325 2400);
WIRE 16 -1 (-325 2400)(-625 2400);
WIRE 16 -1 (-325 2500)(-325 2450);
WIRE 16 -1 (-325 2450)(-625 2450);
WIRE 16 -1 (-325 2550)(-325 2500);
WIRE 16 -1 (-325 2500)(-625 2500);
WIRE 16 -1 (-325 2600)(-325 2550);
WIRE 16 -1 (-325 2550)(-625 2550);
WIRE 16 -1 (-325 2650)(-325 2600);
WIRE 16 -1 (-325 2600)(-625 2600);
WIRE 16 -1 (-325 2700)(-325 2650);
WIRE 16 -1 (-325 2650)(-625 2650);
WIRE 16 -1 (-325 2750)(-325 2700);
WIRE 16 -1 (-325 2700)(-625 2700);
WIRE 16 -1 (-325 2800)(-325 2750);
WIRE 16 -1 (-325 2750)(-625 2750);
WIRE 16 -1 (-325 2850)(-325 2800);
WIRE 16 -1 (-325 2800)(-625 2800);
WIRE 16 -1 (-325 2900)(-325 2850);
WIRE 16 -1 (-325 2850)(-625 2850);
WIRE 16 -1 (-325 2950)(-325 2900);
WIRE 16 -1 (-325 2900)(-625 2900);
WIRE 16 -1 (-325 3000)(-325 2950);
WIRE 16 -1 (-325 2950)(-625 2950);
WIRE 16 -1 (-325 3050)(-325 3000);
WIRE 16 -1 (-325 3000)(-625 3000);
WIRE 16 -1 (-325 3100)(-325 3050);
WIRE 16 -1 (-325 3050)(-625 3050);
WIRE 16 -1 (-325 3150)(-325 3100);
WIRE 16 -1 (-325 3100)(-625 3100);
WIRE 16 -1 (-325 3200)(-325 3150);
WIRE 16 -1 (-325 3150)(-625 3150);
WIRE 16 -1 (-325 3250)(-325 3200);
WIRE 16 -1 (-325 3200)(-625 3200);
WIRE 16 -1 (-325 3300)(-325 3250);
WIRE 16 -1 (-325 3250)(-625 3250);
WIRE 16 -1 (-325 3350)(-325 3300);
WIRE 16 -1 (-325 3300)(-625 3300);
WIRE 16 -1 (-325 3400)(-325 3350);
WIRE 16 -1 (-325 3350)(-625 3350);
WIRE 16 -1 (-325 3450)(-325 3400);
WIRE 16 -1 (-325 3400)(-625 3400);
WIRE 16 -1 (-325 3500)(-325 3450);
WIRE 16 -1 (-325 3450)(-625 3450);
WIRE 16 -1 (-325 3550)(-325 3500);
WIRE 16 -1 (-325 3500)(-625 3500);
WIRE 16 -1 (-325 3600)(-325 3550);
WIRE 16 -1 (-325 3550)(-625 3550);
WIRE 16 -1 (-325 3650)(-325 3600);
WIRE 16 -1 (-325 3600)(-625 3600);
WIRE 16 -1 (-325 3700)(-325 3650);
WIRE 16 -1 (-325 3650)(-625 3650);
WIRE 16 -1 (-325 3750)(-325 3700);
WIRE 16 -1 (-325 3700)(-625 3700);
WIRE 16 -1 (-325 3800)(-325 3750);
WIRE 16 -1 (-325 3750)(-625 3750);
WIRE 16 -1 (-325 3850)(-325 3800);
WIRE 16 -1 (-325 3800)(-625 3800);
WIRE 16 -1 (-325 3900)(-325 3850);
WIRE 16 -1 (-325 3850)(-625 3850);
WIRE 16 -1 (-325 3950)(-325 3900);
WIRE 16 -1 (-325 3900)(-625 3900);
WIRE 16 -1 (-325 4000)(-325 3950);
WIRE 16 -1 (-325 3950)(-625 3950);
WIRE 16 -1 (-325 4050)(-325 4000);
WIRE 16 -1 (-325 4000)(-625 4000);
WIRE 16 -1 (-325 4100)(-325 4050);
WIRE 16 -1 (-325 4050)(-625 4050);
WIRE 16 -1 (-325 4150)(-325 4100);
WIRE 16 -1 (-325 4100)(-625 4100);
WIRE 16 -1 (-325 4200)(-325 4150);
WIRE 16 -1 (-325 4150)(-625 4150);
WIRE 16 -1 (-325 4250)(-325 4200);
WIRE 16 -1 (-325 4200)(-625 4200);
WIRE 16 -1 (-325 4300)(-325 4250);
WIRE 16 -1 (-325 4250)(-625 4250);
WIRE 16 -1 (-325 4350)(-325 4300);
WIRE 16 -1 (-325 4300)(-625 4300);
WIRE 16 -1 (-325 4400)(-325 4350);
WIRE 16 -1 (-325 4350)(-625 4350);
WIRE 16 -1 (-325 4450)(-325 4400);
WIRE 16 -1 (-325 4400)(-625 4400);
WIRE 16 -1 (-325 4500)(-325 4450);
WIRE 16 -1 (-325 4450)(-625 4450);
WIRE 16 -1 (-325 4550)(-325 4500);
WIRE 16 -1 (-325 4500)(-625 4500);
WIRE 16 -1 (-325 4600)(-325 4550);
WIRE 16 -1 (-325 4550)(-625 4550);
WIRE 16 -1 (-325 4650)(-325 4600);
WIRE 16 -1 (-325 4600)(-625 4600);
WIRE 16 -1 (-325 4700)(-325 4650);
WIRE 16 -1 (-325 4650)(-625 4650);
WIRE 16 -1 (-325 4750)(-325 4700);
WIRE 16 -1 (-325 4700)(-625 4700);
WIRE 16 -1 (-325 4800)(-325 4750);
WIRE 16 -1 (-325 4750)(-625 4750);
WIRE 16 -1 (-325 4850)(-325 4800);
WIRE 16 -1 (-325 4800)(-625 4800);
WIRE 16 -1 (-325 4900)(-325 4850);
WIRE 16 -1 (-325 4850)(-625 4850);
WIRE 16 -1 (-325 4950)(-325 4900);
WIRE 16 -1 (-325 4900)(-625 4900);
WIRE 16 -1 (-325 5000)(-325 4950);
WIRE 16 -1 (-325 4950)(-625 4950);
WIRE 16 -1 (-325 5050)(-325 5000);
WIRE 16 -1 (-325 5000)(-625 5000);
WIRE 16 -1 (-325 5100)(-325 5050);
WIRE 16 -1 (-325 5050)(-625 5050);
WIRE 16 -1 (-325 5150)(-325 5100);
WIRE 16 -1 (-325 5100)(-625 5100);
WIRE 16 -1 (-325 5200)(-325 5150);
WIRE 16 -1 (-325 5150)(-625 5150);
WIRE 16 -1 (-325 5250)(-325 5200);
WIRE 16 -1 (-325 5200)(-625 5200);
WIRE 16 -1 (-325 5250)(-625 5250);
WIRE 16 -1 (-2250 5575)(-2250 5700);
WIRE 16 -1 (-2250 5575)(-2825 5575);
WIRE 16 -1 (-2825 5575)(-2825 5700);
WIRE 16 -1 (-2825 5575)(-2825 5500);
WIRE 16 -1 (-2250 6000)(-2250 5900);
WIRE 16 -1 (-2250 6000)(-2125 6000);
WIRE 16 -1 (-2250 6000)(-2825 6000);
WIRE 16 -1 (-2825 5900)(-2825 6000);
WIRE 16 -1 (-2825 6000)(-2825 6075);
WIRE 16 -1 (-2125 5250)(-2125 6000);
WIRE 16 -1 (-1825 5250)(-2125 5250);
WIRE 16 -1 (-2125 5200)(-2125 5250);
WIRE 16 -1 (-1825 5200)(-2125 5200);
WIRE 16 -1 (-2125 5200)(-2125 5150);
WIRE 16 -1 (-2125 5150)(-1825 5150);
WIRE 16 -1 (-7425 3050)(-8075 3050);
FORCEPROP 2 LAST SIG_NAME M_I_CPU1_RESET_N
J 0
(-8060 3060);
DISPLAY 0.489362 (-8060 3060);
WIRE 16 -1 (-7425 3650)(-7625 3650);
WIRE 16 -1 (-7425 3700)(-7625 3700);
WIRE 16 -1 (-7425 3750)(-7625 3750);
WIRE 16 -1 (-7425 3400)(-7625 3400);
WIRE 16 -1 (-7425 3450)(-7625 3450);
WIRE 16 -1 (-7425 3600)(-7625 3600);
WIRE 16 -1 (-7425 3900)(-7625 3900);
WIRE 16 -1 (-7425 3950)(-7625 3950);
WIRE 16 -1 (-7425 4100)(-8225 4100);
FORCEPROP 2 LAST SIG_NAME M_I_CPU1_CLK_DP<0>
J 0
(-8175 4110);
DISPLAY 0.489362 (-8175 4110);
WIRE 16 -1 (-8350 2150)(-8350 2100);
WIRE 16 -1 (-8125 2100)(-8350 2100);
WIRE 16 -1 (-8350 2100)(-8375 2100);
WIRE 16 -1 (-8125 2100)(-8125 2500);
WIRE 16 -1 (-7425 2500)(-8125 2500);
FORCEPROP 2 LAST SIG_NAME PWRGD_CHI_CPU1_DIMM
J 0
(-8035 2510);
DISPLAY 0.489362 (-8035 2510);
FORCEPROP 2 LASTPROP $XRERR UNIQUE?
J 0
(-8275 2510);
DISPLAY 0.638298 (-8275 2510);
PAINT MONO (-8275 2510);
DISPLAY INVISIBLE (-8275 2510);
WIRE 16 -1 (-8575 2100)(-8975 2100);
FORCEPROP 2 LAST SIG_NAME PWRGD_CHGL_CPU1
J 0
(-8935 2110);
DISPLAY 0.489362 (-8935 2110);
WIRE 16 -1 (-7425 1950)(-8225 1950);
FORCEPROP 2 LAST SIG_NAME M_I_CPU1_SA_RSP<0>
J 0
(-8175 1960);
DISPLAY 0.489362 (-8175 1960);
WIRE 16 -1 (-7425 1900)(-8225 1900);
FORCEPROP 2 LAST SIG_NAME M_I_CPU1_SB_RSP<0>
J 0
(-8175 1910);
DISPLAY 0.489362 (-8175 1910);
WIRE 16 -1 (-6375 1325)(-6375 1250);
WIRE 16 -1 (-6375 1325)(-7100 1325);
FORCEPROP 2 LAST SIG_NAME PD_CHI_CPU1_DIMM_SAA
J 0
(-7085 1335);
DISPLAY 0.489362 (-7085 1335);
WIRE 16 -1 (-3650 3350)(-3500 3350);
WIRE 16 -1 (-3650 3300)(-3300 3300);
WIRE 16 -1 (-3650 4400)(-3500 4400);
WIRE 16 -1 (-3650 4350)(-3300 4350);
WIRE 16 -1 (-3500 4300)(-3650 4300);
WIRE 16 -1 (-3650 4250)(-3300 4250);
WIRE 16 -1 (-3650 3100)(-3300 3100);
WIRE 16 -1 (-3500 4200)(-3650 4200);
WIRE 16 -1 (-3500 3050)(-3650 3050);
WIRE 16 -1 (-3650 3000)(-3300 3000);
WIRE 16 -1 (-3650 4050)(-3300 4050);
WIRE 16 -1 (-3650 2950)(-3500 2950);
WIRE 16 -1 (-3650 2900)(-3300 2900);
WIRE 16 -1 (-3650 4000)(-3500 4000);
WIRE 16 -1 (-3300 3950)(-3650 3950);
WIRE 16 -1 (-3500 2850)(-3650 2850);
WIRE 16 -1 (-3650 2800)(-3300 2800);
WIRE 16 -1 (-3500 3900)(-3650 3900);
WIRE 16 -1 (-3650 3850)(-3300 3850);
WIRE 16 -1 (-3500 2750)(-3650 2750);
WIRE 16 -1 (-3650 2700)(-3300 2700);
WIRE 16 -1 (-3500 3800)(-3650 3800);
WIRE 16 -1 (-3650 3750)(-3300 3750);
WIRE 16 -1 (-3500 2650)(-3650 2650);
WIRE 16 -1 (-3650 2600)(-3300 2600);
WIRE 16 -1 (-3500 3700)(-3650 3700);
WIRE 16 -1 (-3650 3650)(-3300 3650);
WIRE 16 -1 (-3650 2550)(-3500 2550);
WIRE 16 -1 (-3650 2500)(-3300 2500);
WIRE 16 -1 (-3650 3600)(-3500 3600);
WIRE 16 -1 (-3650 3550)(-3300 3550);
WIRE 16 -1 (-3500 2450)(-3650 2450);
WIRE 16 -1 (-3650 2400)(-3300 2400);
WIRE 16 -1 (-3500 3500)(-3650 3500);
WIRE 16 -1 (-3650 3450)(-3300 3450);
WIRE 16 -1 (-3500 3150)(-3650 3150);
WIRE 16 -1 (-3650 3200)(-3300 3200);
WIRE 16 -1 (-3500 3250)(-3650 3250);
WIRE 16 -1 (-3500 4100)(-3650 4100);
WIRE 16 -1 (-3300 4150)(-3650 4150);
WIRE 16 -1 (-6225 5350)(-6025 5350);
WIRE 16 -1 (-7425 4500)(-8225 4500);
FORCEPROP 2 LAST SIG_NAME M_I_CPU1_SB_PAR
J 0
(-8175 4510);
DISPLAY 0.489362 (-8175 4510);
WIRE 16 -1 (-7425 4550)(-8225 4550);
FORCEPROP 2 LAST SIG_NAME M_I_CPU1_SA_PAR
J 0
(-8175 4560);
DISPLAY 0.489362 (-8175 4560);
WIRE 16 -1 (-6025 2150)(-6225 2150);
WIRE 16 -1 (-6025 2200)(-6225 2200);
WIRE 16 -1 (-6025 2250)(-6225 2250);
WIRE 16 -1 (-6225 2300)(-6025 2300);
WIRE 16 -1 (-6025 2350)(-6225 2350);
WIRE 16 -1 (-6025 2400)(-6225 2400);
WIRE 16 -1 (-6025 2450)(-6225 2450);
WIRE 16 -1 (-6225 2500)(-6025 2500);
WIRE 16 -1 (-6025 2550)(-6225 2550);
WIRE 16 -1 (-6025 2600)(-6225 2600);
WIRE 16 -1 (-6025 2650)(-6225 2650);
WIRE 16 -1 (-6225 2700)(-6025 2700);
WIRE 16 -1 (-6025 2750)(-6225 2750);
WIRE 16 -1 (-6025 2800)(-6225 2800);
WIRE 16 -1 (-6025 2850)(-6225 2850);
WIRE 16 -1 (-6225 2900)(-6025 2900);
WIRE 16 -1 (-6025 2950)(-6225 2950);
WIRE 16 -1 (-6025 3000)(-6225 3000);
WIRE 16 -1 (-6025 3050)(-6225 3050);
WIRE 16 -1 (-6225 3100)(-6025 3100);
WIRE 16 -1 (-6025 3150)(-6225 3150);
WIRE 16 -1 (-6025 3200)(-6225 3200);
WIRE 16 -1 (-6025 3250)(-6225 3250);
WIRE 16 -1 (-6225 3300)(-6025 3300);
WIRE 16 -1 (-6025 3350)(-6225 3350);
WIRE 16 -1 (-6025 3400)(-6225 3400);
WIRE 16 -1 (-6025 3450)(-6225 3450);
WIRE 16 -1 (-6225 3500)(-6025 3500);
WIRE 16 -1 (-6025 3550)(-6225 3550);
WIRE 16 -1 (-6025 3600)(-6225 3600);
WIRE 16 -1 (-6025 3650)(-6225 3650);
WIRE 16 -1 (-6225 3700)(-6025 3700);
WIRE 16 -1 (-6025 3800)(-6225 3800);
WIRE 16 -1 (-6025 3850)(-6225 3850);
WIRE 16 -1 (-6025 3900)(-6225 3900);
WIRE 16 -1 (-6225 3950)(-6025 3950);
WIRE 16 -1 (-6025 4000)(-6225 4000);
WIRE 16 -1 (-6025 4050)(-6225 4050);
WIRE 16 -1 (-6025 4100)(-6225 4100);
WIRE 16 -1 (-6225 4150)(-6025 4150);
WIRE 16 -1 (-6025 4200)(-6225 4200);
WIRE 16 -1 (-6025 4250)(-6225 4250);
WIRE 16 -1 (-6025 4300)(-6225 4300);
WIRE 16 -1 (-6225 4350)(-6025 4350);
WIRE 16 -1 (-6025 4400)(-6225 4400);
WIRE 16 -1 (-6025 4450)(-6225 4450);
WIRE 16 -1 (-6025 4500)(-6225 4500);
WIRE 16 -1 (-6225 4550)(-6025 4550);
WIRE 16 -1 (-6025 4600)(-6225 4600);
WIRE 16 -1 (-6025 4650)(-6225 4650);
WIRE 16 -1 (-6025 4700)(-6225 4700);
WIRE 16 -1 (-6225 4750)(-6025 4750);
WIRE 16 -1 (-6025 4800)(-6225 4800);
WIRE 16 -1 (-6025 4850)(-6225 4850);
WIRE 16 -1 (-6025 4900)(-6225 4900);
WIRE 16 -1 (-6225 4950)(-6025 4950);
WIRE 16 -1 (-6025 5000)(-6225 5000);
WIRE 16 -1 (-6025 5050)(-6225 5050);
WIRE 16 -1 (-6025 5100)(-6225 5100);
WIRE 16 -1 (-6225 5150)(-6025 5150);
WIRE 16 -1 (-6025 5200)(-6225 5200);
WIRE 16 -1 (-6025 5250)(-6225 5250);
WIRE 16 -1 (-6025 5300)(-6225 5300);
WIRE 16 -1 (-7425 4250)(-8225 4250);
FORCEPROP 2 LAST SIG_NAME M_I_CPU1_SB_CS_N<1>
J 0
(-8175 4260);
DISPLAY 0.489362 (-8175 4260);
WIRE 16 -1 (-7425 4400)(-8225 4400);
FORCEPROP 2 LAST SIG_NAME M_I_CPU1_SA_CS_N<1>
J 0
(-8175 4410);
DISPLAY 0.489362 (-8175 4410);
WIRE 16 -1 (-7425 4200)(-8225 4200);
FORCEPROP 2 LAST SIG_NAME M_I_CPU1_SB_CS_N<0>
J 0
(-8175 4210);
DISPLAY 0.489362 (-8175 4210);
WIRE 16 -1 (-7425 4350)(-8225 4350);
FORCEPROP 2 LAST SIG_NAME M_I_CPU1_SA_CS_N<0>
J 0
(-8175 4360);
DISPLAY 0.489362 (-8175 4360);
WIRE 16 -1 (-7425 4050)(-8225 4050);
FORCEPROP 2 LAST SIG_NAME M_I_CPU1_CLK_DN<0>
J 0
(-8175 4060);
DISPLAY 0.489362 (-8175 4060);
WIRE 16 -1 (-7425 3150)(-7625 3150);
WIRE 16 -1 (-7425 3200)(-7625 3200);
WIRE 16 -1 (-7425 3300)(-7625 3300);
WIRE 16 -1 (-7425 3350)(-7625 3350);
WIRE 16 -1 (-7425 3850)(-7625 3850);
WIRE 16 -1 (-7425 4950)(-7625 4950);
WIRE 16 -1 (-7425 5350)(-7625 5350);
WIRE 16 -1 (-7425 4900)(-7625 4900);
WIRE 16 -1 (-7425 5300)(-7625 5300);
WIRE 16 -1 (-7425 4850)(-7625 4850);
WIRE 16 -1 (-7425 5250)(-7625 5250);
WIRE 16 -1 (-7425 4800)(-7625 4800);
WIRE 16 -1 (-7425 5200)(-7625 5200);
WIRE 16 -1 (-7425 4750)(-7625 4750);
WIRE 16 -1 (-7425 5150)(-7625 5150);
WIRE 16 -1 (-7425 4700)(-7625 4700);
WIRE 16 -1 (-7425 5100)(-7625 5100);
WIRE 16 -1 (-7425 4650)(-7625 4650);
WIRE 16 -1 (-7425 5050)(-7625 5050);
WIRE 16 -1 (-7425 3500)(-7625 3500);
WIRE 16 -1 (-7425 3800)(-7625 3800);
WIRE 16 -1 (-7425 2800)(-8000 2800);
FORCEPROP 2 LAST SIG_NAME I3C_SPD_DDRI_CPU1_SDA
J 0
(-7935 2810);
DISPLAY 0.446809 (-7935 2810);
FORCEPROP 2 LASTPROP $XRERR UNIQUE?
J 0
(-8175 2810);
DISPLAY 0.638298 (-8175 2810);
PAINT MONO (-8175 2810);
DISPLAY INVISIBLE (-8175 2810);
WIRE 16 -1 (-7525 2575)(-7625 2575);
WIRE 16 -1 (-7525 2750)(-7525 2575);
WIRE 16 -1 (-7425 2750)(-7525 2750);
FORCEPROP 2 LAST SIG_NAME I3C_SPD_DDRI_CPU1_SCL
J 0
(-7910 2760);
DISPLAY 0.446809 (-7910 2760);
FORCEPROP 2 LASTPROP $XRERR UNIQUE?
J 0
(-8150 2760);
DISPLAY 0.638298 (-8150 2760);
PAINT MONO (-8150 2760);
DISPLAY INVISIBLE (-8150 2760);
WIRE 16 -1 (-7425 2850)(-8625 2850);
FORCEPROP 2 LAST SIG_NAME PD_CHI_CPU1_DIMM_SAA
J 0
(-8600 2860);
DISPLAY 0.489362 (-8600 2860);
WIRE 16 -1 (-8450 2900)(-7425 2900);
WIRE 16 -1 (-8450 3300)(-8450 2900);
WIRE 16 -1 (-8550 3300)(-8450 3300);
WIRE 16 -1 (-8450 3325)(-8450 3300);
WIRE 16 -1 (-8550 3275)(-8550 3300);
WIRE 16 -1 (-8225 2700)(-8225 2800);
WIRE 16 -1 (-8225 2700)(-8700 2700);
FORCEPROP 2 LAST SIG_NAME I3C_SPD_DDRGL_CPU1_SDA
J 0
(-8710 2710);
DISPLAY 0.489362 (-8710 2710);
WIRE 16 -1 (-8225 2800)(-8200 2800);
WIRE 16 -1 (-7825 2575)(-8350 2575);
FORCEPROP 2 LAST SIG_NAME I3C_SPD_DDRGL_CPU1_SCL
J 0
(-8410 2585);
DISPLAY 0.489362 (-8410 2585);
DOT 1 (-325 5200);
DOT 1 (-325 5150);
DOT 1 (-325 5100);
DOT 1 (-325 5050);
DOT 1 (-325 5000);
DOT 1 (-325 4950);
DOT 1 (-325 4900);
DOT 1 (-325 4850);
DOT 1 (-325 4800);
DOT 1 (-325 4750);
DOT 1 (-325 4700);
DOT 1 (-325 4650);
DOT 1 (-325 4550);
DOT 1 (-325 4600);
DOT 1 (-325 4500);
DOT 1 (-325 4400);
DOT 1 (-325 4450);
DOT 1 (-325 4300);
DOT 1 (-325 4350);
DOT 1 (-325 4250);
DOT 1 (-325 4200);
DOT 1 (-325 4150);
DOT 1 (-325 4050);
DOT 1 (-325 4100);
DOT 1 (-325 4000);
DOT 1 (-325 3950);
DOT 1 (-325 3900);
DOT 1 (-325 3850);
DOT 1 (-325 3800);
DOT 1 (-2125 5200);
DOT 1 (-2125 5250);
DOT 1 (-2125 5050);
DOT 1 (-2125 5000);
DOT 1 (-2125 4950);
DOT 1 (-2125 4900);
DOT 1 (-2125 4750);
DOT 1 (-2125 4700);
DOT 1 (-2125 4650);
DOT 1 (-2125 4550);
DOT 1 (-2125 4600);
DOT 1 (-2125 4500);
DOT 1 (-2125 4400);
DOT 1 (-2125 4450);
DOT 1 (-2125 4300);
DOT 1 (-2125 4350);
DOT 1 (-2125 4250);
DOT 1 (-2125 4200);
DOT 1 (-2125 4150);
DOT 1 (-2125 4050);
DOT 1 (-2125 4100);
DOT 1 (-2125 4000);
DOT 1 (-2125 3950);
DOT 1 (-2125 3900);
DOT 1 (-2125 3850);
DOT 1 (-2125 3800);
DOT 1 (-2125 3750);
DOT 1 (-325 3750);
DOT 1 (-325 3650);
DOT 1 (-325 3700);
DOT 1 (-325 3600);
DOT 1 (-325 3550);
DOT 1 (-325 3500);
DOT 1 (-325 3400);
DOT 1 (-325 3450);
DOT 1 (-325 3350);
DOT 1 (-325 3300);
DOT 1 (-325 3250);
DOT 1 (-325 3150);
DOT 1 (-325 3200);
DOT 1 (-325 3100);
DOT 1 (-325 3050);
DOT 1 (-325 3000);
DOT 1 (-325 2900);
DOT 1 (-325 2950);
DOT 1 (-325 2750);
DOT 1 (-325 2800);
DOT 1 (-325 2850);
DOT 1 (-325 2700);
DOT 1 (-325 2650);
DOT 1 (-325 2600);
DOT 1 (-325 2500);
DOT 1 (-325 2550);
DOT 1 (-325 2450);
DOT 1 (-325 2400);
DOT 1 (-325 2350);
DOT 1 (-325 2250);
DOT 1 (-325 2300);
DOT 1 (-325 2200);
DOT 1 (-325 2150);
DOT 1 (-325 2100);
DOT 1 (-325 2000);
DOT 1 (-325 1900);
DOT 1 (-325 1950);
DOT 1 (-2125 3650);
DOT 1 (-2125 3700);
DOT 1 (-2125 3600);
DOT 1 (-2125 3550);
DOT 1 (-2125 3500);
DOT 1 (-2125 3400);
DOT 1 (-2125 3450);
DOT 1 (-2125 3350);
DOT 1 (-2125 3300);
DOT 1 (-2125 3250);
DOT 1 (-2125 3150);
DOT 1 (-2125 3200);
DOT 1 (-2125 3100);
DOT 1 (-2125 3050);
DOT 1 (-2125 3000);
DOT 1 (-2125 2900);
DOT 1 (-2125 2950);
DOT 1 (-2125 2750);
DOT 1 (-2125 2800);
DOT 1 (-2125 2700);
DOT 1 (-2125 2650);
DOT 1 (-2125 2600);
DOT 1 (-2125 2500);
DOT 1 (-2125 2550);
DOT 1 (-2125 2450);
DOT 1 (-2125 2400);
DOT 1 (-2125 2350);
DOT 1 (-2125 2250);
DOT 1 (-2125 2300);
DOT 1 (-2125 2200);
DOT 1 (-2125 2150);
DOT 1 (-2125 2100);
DOT 1 (-2125 2000);
DOT 1 (-2125 2050);
DOT 1 (-8450 3300);
DOT 1 (-8350 2100);
DOT 1 (-2125 2850);
DOT 1 (-2825 5575);
DOT 1 (-2825 6000);
DOT 1 (-2250 6000);
DOT 1 (-2125 4850);
DOT 1 (-2125 4800);
QUIT
